G04*
G04 #@! TF.GenerationSoftware,Altium Limited,Altium Designer,23.0.1 (38)*
G04*
G04 Layer_Color=128*
%FSLAX25Y25*%
%MOIN*%
G70*
G04*
G04 #@! TF.SameCoordinates,C48E81DB-6E20-4E2D-80E6-7C5AFAA1A21F*
G04*
G04*
G04 #@! TF.FilePolarity,Positive*
G04*
G01*
G75*
%ADD260C,0.00200*%
D260*
X693504Y-105610D02*
X698228D01*
X695866Y-107972D02*
Y-103248D01*
X693504Y-72342D02*
X698228D01*
X695866Y-74705D02*
Y-69980D01*
X686614Y-72342D02*
X691339D01*
X688976Y-74705D02*
Y-69980D01*
X686614Y-105610D02*
X691339D01*
X688976Y-107972D02*
Y-103248D01*
X680315Y-74803D02*
X684252D01*
X682283Y-76772D02*
Y-72835D01*
X680315Y-103150D02*
X684252D01*
X682283Y-105118D02*
Y-101181D01*
X666501Y-135695D02*
X678301D01*
X672401Y-141595D02*
Y-129795D01*
X640158Y-127445D02*
X647244D01*
X643701Y-130988D02*
Y-123902D01*
X640158Y-143945D02*
X647244D01*
X643701Y-147488D02*
Y-140402D01*
X618458Y-127445D02*
X625544D01*
X622001Y-130988D02*
Y-123902D01*
X618458Y-143945D02*
X625544D01*
X622001Y-147488D02*
Y-140402D01*
X639144Y-65206D02*
X642136D01*
X640640Y-66702D02*
Y-63710D01*
X639144Y-17962D02*
X642136D01*
X640640Y-19458D02*
Y-16466D01*
X81289Y-22490D02*
X84281D01*
X82785Y-23986D02*
Y-20994D01*
X81289Y-69734D02*
X84281D01*
X82785Y-71230D02*
Y-68238D01*
X179488Y-120079D02*
X183504D01*
X181496Y-122087D02*
Y-118071D01*
X169488Y-120079D02*
X173504D01*
X171496Y-122087D02*
Y-118071D01*
X159488Y-120079D02*
X163504D01*
X161496Y-122087D02*
Y-118071D01*
X149488Y-120079D02*
X153504D01*
X151496Y-122087D02*
Y-118071D01*
X139488Y-120079D02*
X143504D01*
X141496Y-122087D02*
Y-118071D01*
X266522Y-327165D02*
X274422D01*
X270472Y-331115D02*
Y-323215D01*
X278333Y-327165D02*
X286233D01*
X282283Y-331115D02*
Y-323215D01*
X138570Y-156693D02*
X146470D01*
X142520Y-160643D02*
Y-152743D01*
X290144Y-327165D02*
X298044D01*
X294094Y-331115D02*
Y-323215D01*
X138570Y-316535D02*
X146470D01*
X142520Y-320485D02*
Y-312585D01*
X298412Y-156693D02*
X306312D01*
X302362Y-160643D02*
Y-152743D01*
X138570Y-236614D02*
X146470D01*
X142520Y-240564D02*
Y-232664D01*
X254522Y-327165D02*
X262422D01*
X258472Y-331115D02*
Y-323215D01*
X298412Y-316535D02*
X306312D01*
X302362Y-320485D02*
Y-312585D01*
X242522Y-327165D02*
X250422D01*
X246472Y-331115D02*
Y-323215D01*
X469192Y-308597D02*
X471358D01*
X470275Y-309681D02*
Y-307515D01*
X390452Y-308597D02*
X392618D01*
X391535Y-309681D02*
Y-307515D01*
X339821Y-273410D02*
X341987D01*
X340904Y-274493D02*
Y-272327D01*
X339821Y-194670D02*
X341987D01*
X340904Y-195753D02*
Y-193587D01*
X390461Y-160477D02*
X392628D01*
X391545Y-161560D02*
Y-159394D01*
X469202Y-160477D02*
X471368D01*
X470285Y-161560D02*
Y-159394D01*
X527312Y-194680D02*
X529478D01*
X528395Y-195763D02*
Y-193597D01*
X527312Y-273420D02*
X529478D01*
X528395Y-274503D02*
Y-272337D01*
X280128Y-308632D02*
X290128D01*
X285128Y-313632D02*
Y-303632D01*
X155020Y-314535D02*
X165020D01*
X160020Y-319535D02*
Y-309535D01*
X157520Y-152693D02*
X167520D01*
X162520Y-157693D02*
Y-147693D01*
X254522Y-327165D02*
X262422D01*
X258472Y-331115D02*
Y-323215D01*
X278333Y-327165D02*
X286233D01*
X282283Y-331115D02*
Y-323215D01*
X290144Y-327165D02*
X298044D01*
X294094Y-331115D02*
Y-323215D01*
X298412Y-156693D02*
X306312D01*
X302362Y-160643D02*
Y-152743D01*
X298412Y-316535D02*
X306312D01*
X302362Y-320485D02*
Y-312585D01*
X138570Y-316535D02*
X146470D01*
X142520Y-320485D02*
Y-312585D01*
X138570Y-236614D02*
X146470D01*
X142520Y-240564D02*
Y-232664D01*
X138570Y-156693D02*
X146470D01*
X142520Y-160643D02*
Y-152743D01*
X266522Y-327165D02*
X274422D01*
X270472Y-331115D02*
Y-323215D01*
X242522Y-327165D02*
X250422D01*
X246472Y-331115D02*
Y-323215D01*
X279862Y-164793D02*
X289862D01*
X284862Y-169793D02*
Y-159793D01*
X527110Y-312764D02*
X538921D01*
X533015Y-318670D02*
Y-306858D01*
X330510Y-155764D02*
X342321D01*
X336415Y-161670D02*
Y-149858D01*
X330610Y-312764D02*
X342421D01*
X336515Y-318670D02*
Y-306858D01*
X527110Y-155764D02*
X538921D01*
X533015Y-161670D02*
Y-149858D01*
X600992Y-330039D02*
X607590D01*
X604291Y-333339D02*
Y-326740D01*
X570992Y-330039D02*
X577591D01*
X574291Y-333339D02*
Y-326740D01*
X-21811Y-326781D02*
X-15118D01*
X-18464Y-330128D02*
Y-323435D01*
X-11417Y-316781D02*
X-5512D01*
X-8465Y-319734D02*
Y-313828D01*
X-1811Y-326781D02*
X4882D01*
X1535Y-330128D02*
Y-323435D01*
X-1811Y-306781D02*
X4882D01*
X1535Y-310128D02*
Y-303435D01*
X-21811Y-306781D02*
X-15118D01*
X-18464Y-310128D02*
Y-303435D01*
X-21811Y-273630D02*
X-15118D01*
X-18465Y-276976D02*
Y-270284D01*
X-11417Y-263630D02*
X-5512D01*
X-8465Y-266583D02*
Y-260677D01*
X-1811Y-273630D02*
X4882D01*
X1535Y-276976D02*
Y-270284D01*
X-1811Y-253630D02*
X4882D01*
X1535Y-256976D02*
Y-250284D01*
X-21811Y-253630D02*
X-15118D01*
X-18465Y-256976D02*
Y-250284D01*
X-21811Y-220480D02*
X-15118D01*
X-18465Y-223827D02*
Y-217134D01*
X-11417Y-210480D02*
X-5512D01*
X-8465Y-213433D02*
Y-207528D01*
X-1811Y-220480D02*
X4882D01*
X1535Y-223827D02*
Y-217134D01*
X-1811Y-200480D02*
X4882D01*
X1535Y-203827D02*
Y-197134D01*
X-21811Y-200480D02*
X-15118D01*
X-18465Y-203827D02*
Y-197134D01*
X-21811Y-167332D02*
X-15118D01*
X-18464Y-170679D02*
Y-163986D01*
X-11417Y-157332D02*
X-5512D01*
X-8465Y-160285D02*
Y-154379D01*
X-1811Y-167332D02*
X4882D01*
X1535Y-170679D02*
Y-163986D01*
X-1811Y-147332D02*
X4882D01*
X1535Y-150679D02*
Y-143986D01*
X-21811Y-147332D02*
X-15118D01*
X-18464Y-150679D02*
Y-143986D01*
X639144Y-33710D02*
X642136D01*
X640640Y-35206D02*
Y-32214D01*
X639144Y-17962D02*
X642136D01*
X640640Y-19458D02*
Y-16466D01*
X81289Y-53986D02*
X84281D01*
X82785Y-55482D02*
Y-52490D01*
X81289Y-69734D02*
X84281D01*
X82785Y-71230D02*
Y-68238D01*
X587284Y13937D02*
X590827D01*
X589055Y12165D02*
Y15709D01*
X577283Y13937D02*
X580827D01*
X579055Y12165D02*
Y15709D01*
X567283Y13937D02*
X570827D01*
X569055Y12165D02*
Y15709D01*
X557283Y13937D02*
X560827D01*
X559055Y12165D02*
Y15709D01*
X547284Y13937D02*
X550827D01*
X549055Y12165D02*
Y15709D01*
X537284Y13937D02*
X540827D01*
X539055Y12165D02*
Y15709D01*
X587284Y3937D02*
X590827D01*
X589055Y2165D02*
Y5709D01*
X577283Y3937D02*
X580827D01*
X579055Y2165D02*
Y5709D01*
X567283Y3937D02*
X570827D01*
X569055Y2165D02*
Y5709D01*
X557283Y3937D02*
X560827D01*
X559055Y2165D02*
Y5709D01*
X547284Y3937D02*
X550827D01*
X549055Y2165D02*
Y5709D01*
X537284Y3937D02*
X540827D01*
X539055Y2165D02*
Y5709D01*
X-6260Y0D02*
X6260D01*
X0Y-6260D02*
Y6260D01*
X-6260Y-378395D02*
X6260D01*
X0Y-384655D02*
Y-372135D01*
X670138Y-74409D02*
X670938D01*
X670538Y-74809D02*
Y-74009D01*
X668038Y-74409D02*
X668838D01*
X668438Y-74809D02*
Y-74009D01*
X676372Y-54331D02*
X677172D01*
X676772Y-54731D02*
Y-53931D01*
X676372Y-51575D02*
X677172D01*
X676772Y-51975D02*
Y-51175D01*
X83679Y-105653D02*
X84479D01*
X84079Y-106053D02*
Y-105253D01*
X62586Y-112803D02*
X63386D01*
X62986Y-113203D02*
Y-112403D01*
X62099Y-117255D02*
X62899D01*
X62499Y-117655D02*
Y-116855D01*
X678780Y-340551D02*
X691299D01*
X685039Y-346811D02*
Y-334291D01*
X141581Y-347043D02*
X142381D01*
X141981Y-347443D02*
Y-346643D01*
X142120Y-342913D02*
X142920D01*
X142520Y-343313D02*
Y-342513D01*
X197992Y-366842D02*
X198792D01*
X198392Y-367242D02*
Y-366442D01*
X196301Y-370523D02*
X197101D01*
X196701Y-370923D02*
Y-370123D01*
X680309Y-216929D02*
X681109D01*
X680709Y-217329D02*
Y-216529D01*
X671253Y-217323D02*
X672053D01*
X671654Y-217723D02*
Y-216923D01*
X585033Y-114961D02*
X585833D01*
X585433Y-115361D02*
Y-114561D01*
X583852Y-117717D02*
X584652D01*
X584252Y-118116D02*
Y-117316D01*
X366529Y-75984D02*
X367329D01*
X366929Y-76384D02*
Y-75584D01*
X366529Y-83071D02*
X367329D01*
X366929Y-83471D02*
Y-82671D01*
X366529Y-86614D02*
X367329D01*
X366929Y-87014D02*
Y-86214D01*
X366529Y-89370D02*
X367329D01*
X366929Y-89770D02*
Y-88970D01*
X366529Y-79528D02*
X367329D01*
X366929Y-79928D02*
Y-79128D01*
X679521Y-160236D02*
X680321D01*
X679921Y-160636D02*
Y-159836D01*
X684246Y-161811D02*
X685046D01*
X684646Y-162211D02*
Y-161411D01*
X688970Y-161417D02*
X689770D01*
X689370Y-161817D02*
Y-161017D01*
X689364Y-164567D02*
X690164D01*
X689764Y-164967D02*
Y-164167D01*
X689364Y-168110D02*
X690164D01*
X689764Y-168510D02*
Y-167710D01*
X624600Y-48080D02*
X625400D01*
X625000Y-48480D02*
Y-47680D01*
X476545Y-173228D02*
X477345D01*
X476945Y-173628D02*
Y-172828D01*
X555112Y-218504D02*
X555912D01*
X555512Y-218904D02*
Y-218104D01*
X381096Y-127165D02*
X381896D01*
X381496Y-127565D02*
Y-126765D01*
X378340Y-123622D02*
X379140D01*
X378740Y-124022D02*
Y-123222D01*
X377159Y-135433D02*
X377959D01*
X377559Y-135833D02*
Y-135033D01*
X381490Y-137402D02*
X382290D01*
X381890Y-137802D02*
Y-137002D01*
X377159Y-142126D02*
X377959D01*
X377559Y-142526D02*
Y-141726D01*
X381096Y-140945D02*
X381896D01*
X381496Y-141345D02*
Y-140545D01*
X473616Y-176378D02*
X474416D01*
X474016Y-176778D02*
Y-175978D01*
X459786Y-175448D02*
X460586D01*
X460186Y-175848D02*
Y-175048D01*
X577768Y-80778D02*
X578568D01*
X578168Y-81178D02*
Y-80378D01*
X529627Y-172987D02*
X530427D01*
X530027Y-173388D02*
Y-172588D01*
X532644Y-176225D02*
X533444D01*
X533044Y-176625D02*
Y-175825D01*
X495269Y-222047D02*
X496069D01*
X495669Y-222447D02*
Y-221647D01*
X499994Y-222835D02*
X500794D01*
X500394Y-223235D02*
Y-222435D01*
X157080Y-361811D02*
X157880D01*
X157480Y-362211D02*
Y-361411D01*
X153143Y-358661D02*
X153943D01*
X153543Y-359061D02*
Y-358261D01*
X153143Y-361811D02*
X153943D01*
X153543Y-362211D02*
Y-361411D01*
X155112Y-361811D02*
X155912D01*
X155512Y-362211D02*
Y-361411D01*
X155112Y-358661D02*
X155912D01*
X155512Y-359061D02*
Y-358261D01*
X157080Y-358661D02*
X157880D01*
X157480Y-359061D02*
Y-358261D01*
X644088Y-170472D02*
X644888D01*
X644488Y-170872D02*
Y-170072D01*
X644219Y-166285D02*
X645019D01*
X644619Y-166685D02*
Y-165885D01*
X644169Y-162910D02*
X644969D01*
X644569Y-163310D02*
Y-162510D01*
X644088Y-159843D02*
X644888D01*
X644488Y-160242D02*
Y-159442D01*
X435427Y-103543D02*
X436227D01*
X435827Y-103943D02*
Y-103143D01*
X402319Y-112334D02*
X403119D01*
X402719Y-112733D02*
Y-111934D01*
X409500Y-136559D02*
X410300D01*
X409900Y-136959D02*
Y-136159D01*
X430092Y-136473D02*
X430892D01*
X430492Y-136873D02*
Y-136073D01*
X414167Y-137402D02*
X414967D01*
X414567Y-137802D02*
Y-137002D01*
X436214Y-136614D02*
X437014D01*
X436614Y-137014D02*
Y-136214D01*
X442907Y-111024D02*
X443707D01*
X443307Y-111424D02*
Y-110624D01*
X664566Y-316582D02*
X665366D01*
X664966Y-316982D02*
Y-316182D01*
X664561Y-325984D02*
X665361D01*
X664961Y-326384D02*
Y-325584D01*
X691637Y-315878D02*
X692437D01*
X692037Y-316278D02*
Y-315478D01*
X691726Y-322441D02*
X692526D01*
X692126Y-322841D02*
Y-322041D01*
X256497Y-112001D02*
X257297D01*
X256897Y-112401D02*
Y-111601D01*
X254718Y-118504D02*
X255518D01*
X255118Y-118904D02*
Y-118104D01*
X253976Y-125747D02*
X254776D01*
X254376Y-126146D02*
Y-125347D01*
X240850Y-126247D02*
X241650D01*
X241250Y-126647D02*
Y-125847D01*
X237789Y-116142D02*
X238589D01*
X238189Y-116542D02*
Y-115742D01*
X245663Y-111024D02*
X246463D01*
X246063Y-111424D02*
Y-110624D01*
X248025Y-129134D02*
X248825D01*
X248425Y-129534D02*
Y-128734D01*
X240677Y-118805D02*
X241477D01*
X241077Y-119204D02*
Y-118404D01*
X255112Y-121260D02*
X255912D01*
X255512Y-121660D02*
Y-120860D01*
X253313Y-109190D02*
X254113D01*
X253713Y-109590D02*
Y-108790D01*
X253290Y-111960D02*
X254090D01*
X253690Y-112360D02*
Y-111560D01*
X267317Y-123622D02*
X268116D01*
X267717Y-124022D02*
Y-123222D01*
X271253Y-122835D02*
X272054D01*
X271654Y-123235D02*
Y-122435D01*
X266923Y-132677D02*
X267723D01*
X267323Y-133077D02*
Y-132277D01*
X271647Y-131496D02*
X272447D01*
X272047Y-131896D02*
Y-131096D01*
X244264Y-106952D02*
X245064D01*
X244664Y-107352D02*
Y-106552D01*
X228424Y-104850D02*
X229224D01*
X228824Y-105250D02*
Y-104450D01*
X577553Y-83858D02*
X578353D01*
X577953Y-84258D02*
Y-83458D01*
X618498Y-82284D02*
X619298D01*
X618898Y-82683D02*
Y-81884D01*
X611805Y-87008D02*
X612605D01*
X612205Y-87408D02*
Y-86608D01*
X608655Y-92520D02*
X609455D01*
X609055Y-92920D02*
Y-92120D01*
X620559Y-100047D02*
X621359D01*
X620959Y-100447D02*
Y-99647D01*
X612198Y-100000D02*
X612998D01*
X612598Y-100400D02*
Y-99600D01*
X628734Y-102756D02*
X629534D01*
X629134Y-103156D02*
Y-102356D01*
X631415Y-83784D02*
X632214D01*
X631814Y-84184D02*
Y-83384D01*
X628701Y-90137D02*
X629501D01*
X629101Y-90537D02*
Y-89737D01*
X622828Y-93307D02*
X623628D01*
X623228Y-93707D02*
Y-92907D01*
X616135Y-84646D02*
X616935D01*
X616535Y-85046D02*
Y-84246D01*
X616529Y-100000D02*
X617329D01*
X616929Y-100400D02*
Y-99600D01*
X598879Y-82981D02*
X599679D01*
X599279Y-83381D02*
Y-82581D01*
X596827Y-77103D02*
X597627D01*
X597227Y-77503D02*
Y-76703D01*
X601344Y-98051D02*
X602144D01*
X601745Y-98451D02*
Y-97651D01*
X587972Y-100945D02*
X588772D01*
X588372Y-101345D02*
Y-100545D01*
X566923Y-94095D02*
X567723D01*
X567323Y-94494D02*
Y-93695D01*
X568891Y-91339D02*
X569691D01*
X569291Y-91739D02*
Y-90939D01*
X568104Y-88189D02*
X568904D01*
X568504Y-88589D02*
Y-87789D01*
X579521Y-101969D02*
X580321D01*
X579921Y-102368D02*
Y-101568D01*
X584363Y-100116D02*
X585163D01*
X584763Y-100516D02*
Y-99716D01*
X588576Y-86221D02*
X589376D01*
X588976Y-86620D02*
Y-85821D01*
X599994Y-87795D02*
X600794D01*
X600394Y-88195D02*
Y-87395D01*
X592120Y-93307D02*
X592920D01*
X592520Y-93707D02*
Y-92907D01*
X666529Y-98032D02*
X667329D01*
X666929Y-98431D02*
Y-97632D01*
X662139Y-107066D02*
X662939D01*
X662539Y-107466D02*
Y-106666D01*
X667316Y-106693D02*
X668117D01*
X667717Y-107093D02*
Y-106293D01*
X696362Y-63288D02*
X697162D01*
X696762Y-63688D02*
Y-62888D01*
X696177Y-51453D02*
X696977D01*
X696577Y-51853D02*
Y-51053D01*
X675190Y-42520D02*
X675990D01*
X675591Y-42920D02*
Y-42120D01*
X685316Y-22157D02*
X686116D01*
X685716Y-22557D02*
Y-21757D01*
X679117Y-26553D02*
X679917D01*
X679517Y-26952D02*
Y-26153D01*
X679117Y-37023D02*
X679917D01*
X679517Y-37423D02*
Y-36623D01*
X693514Y-33393D02*
X694314D01*
X693915Y-33793D02*
Y-32993D01*
X686328Y-33442D02*
X687128D01*
X686728Y-33842D02*
Y-33042D01*
X685919Y-43553D02*
X686719D01*
X686319Y-43953D02*
Y-43153D01*
X682727Y-66209D02*
X683527D01*
X683127Y-66609D02*
Y-65809D01*
X689066Y-66165D02*
X689866D01*
X689466Y-66565D02*
Y-65765D01*
X679682Y-64183D02*
X680482D01*
X680082Y-64583D02*
Y-63783D01*
X675526Y-72691D02*
X676326D01*
X675926Y-73091D02*
Y-72291D01*
X660319Y-75726D02*
X661119D01*
X660719Y-76126D02*
Y-75327D01*
X693694Y-62205D02*
X694494D01*
X694095Y-62605D02*
Y-61805D01*
X693577Y-53201D02*
X694377D01*
X693977Y-53601D02*
Y-52801D01*
X675978Y-83858D02*
X676778D01*
X676378Y-84258D02*
Y-83458D01*
X538183Y-111811D02*
X538983D01*
X538583Y-112211D02*
Y-111411D01*
X538833Y-115729D02*
X539633D01*
X539233Y-116129D02*
Y-115329D01*
X568692Y-108048D02*
X569492D01*
X569092Y-108448D02*
Y-107648D01*
X545986Y-109024D02*
X546786D01*
X546386Y-109424D02*
Y-108624D01*
X547693Y-185219D02*
X548493D01*
X548093Y-185619D02*
Y-184819D01*
X548025Y-181890D02*
X548825D01*
X548425Y-182290D02*
Y-181490D01*
X548419Y-178740D02*
X549219D01*
X548819Y-179140D02*
Y-178340D01*
X546844Y-157087D02*
X547644D01*
X547244Y-157487D02*
Y-156687D01*
X546844Y-144488D02*
X547644D01*
X547244Y-144888D02*
Y-144088D01*
X524010Y-135827D02*
X524810D01*
X524409Y-136227D02*
Y-135427D01*
X531401Y-127495D02*
X532201D01*
X531801Y-127895D02*
Y-127095D01*
X539500Y-140766D02*
X540300D01*
X539900Y-141166D02*
Y-140366D01*
X570072Y-137795D02*
X570872D01*
X570472Y-138195D02*
Y-137395D01*
X579521Y-133465D02*
X580321D01*
X579921Y-133865D02*
Y-133065D01*
X574010Y-133465D02*
X574810D01*
X574409Y-133865D02*
Y-133065D01*
X570466Y-133465D02*
X571266D01*
X570866Y-133865D02*
Y-133065D01*
X571647Y-129921D02*
X572447D01*
X572047Y-130321D02*
Y-129521D01*
X575978Y-129921D02*
X576778D01*
X576378Y-130321D02*
Y-129521D01*
X579915Y-129921D02*
X580715D01*
X580315Y-130321D02*
Y-129521D01*
X646057Y-156693D02*
X646857D01*
X646457Y-157093D02*
Y-156293D01*
X642120Y-156693D02*
X642920D01*
X642520Y-157093D02*
Y-156293D01*
X634639Y-216142D02*
X635439D01*
X635039Y-216542D02*
Y-215742D01*
X608261Y-236221D02*
X609061D01*
X608661Y-236620D02*
Y-235821D01*
X572041Y-227165D02*
X572841D01*
X572441Y-227565D02*
Y-226765D01*
X678041Y-292586D02*
X678841D01*
X678441Y-292986D02*
Y-292186D01*
X677947Y-297244D02*
X678747D01*
X678346Y-297644D02*
Y-296844D01*
X639364Y-283858D02*
X640164D01*
X639764Y-284258D02*
Y-283458D01*
X554324Y-294882D02*
X555124D01*
X554724Y-295282D02*
Y-294482D01*
X564954Y-292913D02*
X565754D01*
X565354Y-293313D02*
Y-292513D01*
X630177Y-278001D02*
X630977D01*
X630577Y-278401D02*
Y-277601D01*
X582474Y-294291D02*
X583274D01*
X582874Y-294691D02*
Y-293891D01*
X680309Y-212205D02*
X681109D01*
X680709Y-212605D02*
Y-211805D01*
X673222Y-213779D02*
X674022D01*
X673622Y-214179D02*
Y-213380D01*
X669285Y-213779D02*
X670085D01*
X669685Y-214179D02*
Y-213380D01*
X665742Y-212992D02*
X666542D01*
X666142Y-213392D02*
Y-212592D01*
X599164Y-178940D02*
X599964D01*
X599564Y-179340D02*
Y-178540D01*
X594482Y-179134D02*
X595282D01*
X594882Y-179534D02*
Y-178734D01*
X589364Y-179134D02*
X590164D01*
X589764Y-179534D02*
Y-178734D01*
X584246Y-178740D02*
X585046D01*
X584646Y-179140D02*
Y-178340D01*
X635427Y-187795D02*
X636227D01*
X635827Y-188195D02*
Y-187395D01*
X635033Y-184252D02*
X635833D01*
X635433Y-184652D02*
Y-183852D01*
X652356Y-164961D02*
X653156D01*
X652756Y-165361D02*
Y-164561D01*
X657080Y-164567D02*
X657880D01*
X657480Y-164967D02*
Y-164167D01*
X662592Y-164961D02*
X663392D01*
X662992Y-165361D02*
Y-164561D01*
X668104Y-164961D02*
X668904D01*
X668504Y-165361D02*
Y-164561D01*
X681096Y-179528D02*
X681896D01*
X681496Y-179928D02*
Y-179128D01*
X676765Y-172441D02*
X677565D01*
X677165Y-172841D02*
Y-172041D01*
X672828Y-172441D02*
X673628D01*
X673228Y-172841D02*
Y-172041D01*
X674797Y-200000D02*
X675597D01*
X675197Y-200400D02*
Y-199600D01*
X678340Y-200000D02*
X679140D01*
X678740Y-200400D02*
Y-199600D01*
X681490Y-200000D02*
X682290D01*
X681890Y-200400D02*
Y-199600D01*
X681490Y-196850D02*
X682290D01*
X681890Y-197250D02*
Y-196450D01*
X678340Y-196850D02*
X679140D01*
X678740Y-197250D02*
Y-196450D01*
X675190Y-196457D02*
X675990D01*
X675591Y-196857D02*
Y-196057D01*
X652356Y-218504D02*
X653156D01*
X652756Y-218904D02*
Y-218104D01*
X649600Y-231102D02*
X650400D01*
X650000Y-231502D02*
Y-230702D01*
X646034Y-231245D02*
X646834D01*
X646434Y-231645D02*
Y-230845D01*
X598025Y-198819D02*
X598825D01*
X598425Y-199219D02*
Y-198419D01*
X594876Y-198819D02*
X595676D01*
X595276Y-199219D02*
Y-198419D01*
X591726Y-198819D02*
X592526D01*
X592126Y-199219D02*
Y-198419D01*
X589364Y-198819D02*
X590164D01*
X589764Y-199219D02*
Y-198419D01*
X586608Y-198819D02*
X587408D01*
X587008Y-199219D02*
Y-198419D01*
X569679Y-200000D02*
X570479D01*
X570079Y-200400D02*
Y-199600D01*
X548898Y-191988D02*
X549698D01*
X549298Y-192388D02*
Y-191588D01*
X599600Y-248425D02*
X600400D01*
X600000Y-248825D02*
Y-248025D01*
X616135Y-255512D02*
X616935D01*
X616535Y-255912D02*
Y-255112D01*
X611805Y-251575D02*
X612605D01*
X612205Y-251975D02*
Y-251175D01*
X624403Y-255906D02*
X625203D01*
X624803Y-256306D02*
Y-255505D01*
X624403Y-251575D02*
X625203D01*
X624803Y-251975D02*
Y-251175D01*
X624010Y-248031D02*
X624810D01*
X624409Y-248431D02*
Y-247632D01*
X611017Y-247638D02*
X611817D01*
X611417Y-248038D02*
Y-247238D01*
X604718Y-244488D02*
X605518D01*
X605118Y-244888D02*
Y-244088D01*
X672828Y-251181D02*
X673628D01*
X673228Y-251581D02*
Y-250781D01*
X672435Y-257087D02*
X673235D01*
X672835Y-257487D02*
Y-256687D01*
X673222Y-261417D02*
X674022D01*
X673622Y-261817D02*
Y-261017D01*
X675978Y-266142D02*
X676778D01*
X676378Y-266542D02*
Y-265742D01*
X676372Y-270866D02*
X677172D01*
X676772Y-271266D02*
Y-270466D01*
X670860Y-274803D02*
X671660D01*
X671260Y-275203D02*
Y-274403D01*
X670860Y-278740D02*
X671660D01*
X671260Y-279140D02*
Y-278340D01*
X671253Y-283071D02*
X672053D01*
X671654Y-283471D02*
Y-282671D01*
X683458Y-310630D02*
X684258D01*
X683858Y-311030D02*
Y-310230D01*
X683316Y-298538D02*
X684116D01*
X683716Y-298938D02*
Y-298138D01*
X651175Y-275197D02*
X651975D01*
X651575Y-275597D02*
Y-274797D01*
X648419Y-278740D02*
X649219D01*
X648819Y-279140D02*
Y-278340D01*
X651962Y-279528D02*
X652762D01*
X652362Y-279928D02*
Y-279128D01*
X656687Y-279528D02*
X657487D01*
X657087Y-279928D02*
Y-279128D01*
X653931Y-283858D02*
X654731D01*
X654331Y-284258D02*
Y-283458D01*
X649600Y-283858D02*
X650400D01*
X650000Y-284258D02*
Y-283458D01*
X646057Y-283858D02*
X646857D01*
X646457Y-284258D02*
Y-283458D01*
X637395Y-297638D02*
X638195D01*
X637795Y-298038D02*
Y-297238D01*
X584639Y-249606D02*
X585439D01*
X585039Y-250006D02*
Y-249206D01*
X590151Y-266535D02*
X590951D01*
X590551Y-266935D02*
Y-266135D01*
X587789Y-263386D02*
X588589D01*
X588189Y-263786D02*
Y-262986D01*
X585033Y-253937D02*
X585833D01*
X585433Y-254337D02*
Y-253537D01*
X585033Y-257480D02*
X585833D01*
X585433Y-257880D02*
Y-257080D01*
X581096Y-257480D02*
X581896D01*
X581496Y-257880D02*
Y-257080D01*
X577553Y-257480D02*
X578353D01*
X577953Y-257880D02*
Y-257080D01*
X559443Y-257087D02*
X560243D01*
X559842Y-257487D02*
Y-256687D01*
X578734Y-195276D02*
X579534D01*
X579134Y-195676D02*
Y-194876D01*
X574403Y-195276D02*
X575203D01*
X574803Y-195676D02*
Y-194876D01*
X577553Y-198819D02*
X578353D01*
X577953Y-199219D02*
Y-198419D01*
X589757Y-226378D02*
X590557D01*
X590158Y-226778D02*
Y-225978D01*
X585820Y-226772D02*
X586621D01*
X586221Y-227172D02*
Y-226372D01*
X579521Y-227559D02*
X580321D01*
X579921Y-227959D02*
Y-227159D01*
X576372Y-228740D02*
X577172D01*
X576772Y-229140D02*
Y-228340D01*
X636608Y-238583D02*
X637408D01*
X637008Y-238983D02*
Y-238183D01*
X608261Y-242126D02*
X609061D01*
X608661Y-242526D02*
Y-241726D01*
X590151Y-242520D02*
X590951D01*
X590551Y-242920D02*
Y-242120D01*
X586137Y-234843D02*
X586937D01*
X586537Y-235243D02*
Y-234443D01*
X546450Y-213779D02*
X547250D01*
X546850Y-214179D02*
Y-213380D01*
X548419Y-196063D02*
X549219D01*
X548819Y-196463D02*
Y-195663D01*
X546844Y-203150D02*
X547644D01*
X547244Y-203550D02*
Y-202750D01*
X554324Y-207874D02*
X555124D01*
X554724Y-208274D02*
Y-207474D01*
X548813Y-207874D02*
X549613D01*
X549213Y-208274D02*
Y-207474D01*
X568891Y-194095D02*
X569691D01*
X569291Y-194494D02*
Y-193694D01*
X581096Y-198819D02*
X581896D01*
X581496Y-199219D02*
Y-198419D01*
X573222Y-198819D02*
X574022D01*
X573622Y-199219D02*
Y-198419D01*
X570762Y-284136D02*
X571562D01*
X571162Y-284536D02*
Y-283736D01*
X577553Y-284646D02*
X578353D01*
X577953Y-285046D02*
Y-284246D01*
X574403Y-284252D02*
X575203D01*
X574803Y-284652D02*
Y-283852D01*
X567710Y-284252D02*
X568510D01*
X568110Y-284652D02*
Y-283852D01*
X567316Y-259055D02*
X568117D01*
X567717Y-259455D02*
Y-258655D01*
X566135Y-255906D02*
X566935D01*
X566535Y-256306D02*
Y-255505D01*
X569679Y-255906D02*
X570479D01*
X570079Y-256306D02*
Y-255505D01*
X548025Y-253543D02*
X548825D01*
X548425Y-253943D02*
Y-253143D01*
X545269Y-253937D02*
X546069D01*
X545669Y-254337D02*
Y-253537D01*
X544728Y-280872D02*
X545528D01*
X545128Y-281272D02*
Y-280472D01*
X544509Y-287437D02*
X545309D01*
X544909Y-287837D02*
Y-287037D01*
X544876Y-294094D02*
X545676D01*
X545276Y-294495D02*
Y-293694D01*
X544876Y-275197D02*
X545676D01*
X545276Y-275597D02*
Y-274797D01*
X544876Y-270866D02*
X545676D01*
X545276Y-271266D02*
Y-270466D01*
X544088Y-265748D02*
X544888D01*
X544488Y-266148D02*
Y-265348D01*
X556687Y-261417D02*
X557487D01*
X557087Y-261817D02*
Y-261017D01*
X556228Y-258042D02*
X557028D01*
X556628Y-258442D02*
Y-257642D01*
X569147Y-287223D02*
X569947D01*
X569548Y-287623D02*
Y-286823D01*
X594876Y-291732D02*
X595676D01*
X595276Y-292132D02*
Y-291332D01*
X612198Y-291732D02*
X612998D01*
X612598Y-292132D02*
Y-291332D01*
X627159Y-296457D02*
X627959D01*
X627559Y-296857D02*
Y-296057D01*
X562986Y-257874D02*
X563786D01*
X563386Y-258274D02*
Y-257474D01*
X572041Y-258268D02*
X572841D01*
X572441Y-258668D02*
Y-257868D01*
X475584Y-127165D02*
X476384D01*
X475984Y-127565D02*
Y-126765D01*
X479720Y-132365D02*
X480520D01*
X480120Y-132765D02*
Y-131965D01*
X469285Y-133465D02*
X470085D01*
X469685Y-133865D02*
Y-133065D01*
X472828Y-105905D02*
X473628D01*
X473228Y-106306D02*
Y-105506D01*
X488183Y-132283D02*
X488983D01*
X488583Y-132684D02*
Y-131884D01*
X505899Y-129921D02*
X506699D01*
X506299Y-130321D02*
Y-129521D01*
X497632Y-132283D02*
X498431D01*
X498032Y-132684D02*
Y-131884D01*
X505807Y-127333D02*
X506607D01*
X506207Y-127733D02*
Y-126933D01*
X505506Y-123622D02*
X506306D01*
X505905Y-124022D02*
Y-123222D01*
X472041Y-113779D02*
X472841D01*
X472441Y-114180D02*
Y-113380D01*
X483084Y-105840D02*
X483884D01*
X483484Y-106240D02*
Y-105440D01*
X504303Y-106672D02*
X505103D01*
X504703Y-107072D02*
Y-106272D01*
X507868Y-117323D02*
X508668D01*
X508268Y-117723D02*
Y-116923D01*
X501269Y-116601D02*
X502069D01*
X501669Y-117001D02*
Y-116201D01*
X499913Y-105734D02*
X500713D01*
X500313Y-106134D02*
Y-105334D01*
X476372Y-123622D02*
X477172D01*
X476772Y-124022D02*
Y-123222D01*
X470073Y-123622D02*
X470872D01*
X470472Y-124022D02*
Y-123222D01*
X444107Y-309009D02*
X444907D01*
X444507Y-309409D02*
Y-308609D01*
X448419Y-309055D02*
X449219D01*
X448819Y-309455D02*
Y-308655D01*
X457080Y-306693D02*
X457880D01*
X457480Y-307093D02*
Y-306293D01*
X451175Y-309055D02*
X451975D01*
X451575Y-309455D02*
Y-308655D01*
X436648Y-308863D02*
X437448D01*
X437048Y-309263D02*
Y-308463D01*
X430702Y-308268D02*
X431502D01*
X431102Y-308668D02*
Y-307868D01*
X461411Y-327165D02*
X462211D01*
X461811Y-327565D02*
Y-326765D01*
X456293Y-327165D02*
X457093D01*
X456693Y-327565D02*
Y-326765D01*
X454324Y-327165D02*
X455124D01*
X454724Y-327565D02*
Y-326765D01*
X449994Y-327165D02*
X450794D01*
X450394Y-327565D02*
Y-326765D01*
X447632Y-327165D02*
X448431D01*
X448032Y-327565D02*
Y-326765D01*
X443301Y-327165D02*
X444101D01*
X443701Y-327565D02*
Y-326765D01*
X441332Y-327165D02*
X442132D01*
X441732Y-327565D02*
Y-326765D01*
X436214Y-327165D02*
X437014D01*
X436614Y-327565D02*
Y-326765D01*
X429128Y-326772D02*
X429928D01*
X429528Y-327172D02*
Y-326372D01*
X434246Y-327559D02*
X435046D01*
X434646Y-327959D02*
Y-327159D01*
X517937Y-159634D02*
X518737D01*
X518337Y-160034D02*
Y-159234D01*
X515302Y-162803D02*
X516102D01*
X515702Y-163203D02*
Y-162403D01*
X498293Y-188351D02*
X499093D01*
X498693Y-188751D02*
Y-187951D01*
X498419Y-183858D02*
X499219D01*
X498819Y-184258D02*
Y-183458D01*
X498711Y-179528D02*
X499511D01*
X499111Y-179928D02*
Y-179128D01*
X657714Y-56714D02*
X658514D01*
X658114Y-57114D02*
Y-56314D01*
X657045Y-63525D02*
X657845D01*
X657445Y-63925D02*
Y-63125D01*
X657653Y-71188D02*
X658453D01*
X658053Y-71588D02*
Y-70788D01*
X623111Y-62552D02*
X623911D01*
X623511Y-62952D02*
Y-62152D01*
X622828Y-55118D02*
X623628D01*
X623228Y-55518D02*
Y-54718D01*
X623222Y-70866D02*
X624022D01*
X623622Y-71266D02*
Y-70466D01*
X43301Y-29921D02*
X44101D01*
X43701Y-30321D02*
Y-29521D01*
X55506Y-31496D02*
X56305D01*
X55905Y-31896D02*
Y-31096D01*
X110624Y-33071D02*
X111424D01*
X111024Y-33471D02*
Y-32671D01*
X125191Y-32283D02*
X125991D01*
X125591Y-32684D02*
Y-31883D01*
X63773Y-42520D02*
X64573D01*
X64173Y-42920D02*
Y-42120D01*
X100781Y-18504D02*
X101581D01*
X101181Y-18904D02*
Y-18104D01*
X101175Y-42126D02*
X101975D01*
X101575Y-42526D02*
Y-41726D01*
X669679Y-9449D02*
X670479D01*
X670079Y-9849D02*
Y-9049D01*
X672828Y-29528D02*
X673628D01*
X673228Y-29928D02*
Y-29128D01*
X671253Y-62598D02*
X672053D01*
X671654Y-62998D02*
Y-62198D01*
X671253Y-41339D02*
X672053D01*
X671654Y-41739D02*
Y-40939D01*
X659049Y-49213D02*
X659849D01*
X659449Y-49613D02*
Y-48813D01*
X595663Y-53937D02*
X596463D01*
X596063Y-54337D02*
Y-53537D01*
X602356Y-39764D02*
X603156D01*
X602756Y-40164D02*
Y-39364D01*
X659836Y-14961D02*
X660636D01*
X660236Y-15361D02*
Y-14561D01*
X614167Y-44882D02*
X614967D01*
X614567Y-45282D02*
Y-44482D01*
X423061Y-178869D02*
X423861D01*
X423461Y-179269D02*
Y-178469D01*
X144471Y-131609D02*
X145271D01*
X144871Y-132009D02*
Y-131209D01*
X119679Y-263386D02*
X120479D01*
X120079Y-263786D02*
Y-262986D01*
X314017Y-228033D02*
X314817D01*
X314417Y-228433D02*
Y-227633D01*
X314224Y-231391D02*
X315023D01*
X314623Y-231791D02*
Y-230991D01*
X325584Y-272441D02*
X326384D01*
X325984Y-272841D02*
Y-272041D01*
X416435Y-196581D02*
X417235D01*
X416835Y-196981D02*
Y-196181D01*
X411411Y-196850D02*
X412211D01*
X411811Y-197250D02*
Y-196450D01*
X570466Y-70472D02*
X571266D01*
X570866Y-70872D02*
Y-70072D01*
X570466Y-72441D02*
X571266D01*
X570866Y-72841D02*
Y-72041D01*
X570466Y-74410D02*
X571266D01*
X570866Y-74809D02*
Y-74010D01*
X573616Y-70472D02*
X574416D01*
X574016Y-70872D02*
Y-70072D01*
X573616Y-72441D02*
X574416D01*
X574016Y-72841D02*
Y-72041D01*
X573616Y-74410D02*
X574416D01*
X574016Y-74809D02*
Y-74010D01*
X350387Y-116929D02*
X351187D01*
X350787Y-117329D02*
Y-116529D01*
X352356Y-116929D02*
X353156D01*
X352756Y-117329D02*
Y-116529D01*
X354324Y-116929D02*
X355124D01*
X354724Y-117329D02*
Y-116529D01*
X350387Y-113779D02*
X351187D01*
X350787Y-114180D02*
Y-113380D01*
X352356Y-113779D02*
X353156D01*
X352756Y-114180D02*
Y-113380D01*
X354324Y-113779D02*
X355124D01*
X354724Y-114180D02*
Y-113380D01*
X378734Y-137795D02*
X379534D01*
X379134Y-138195D02*
Y-137395D01*
X378340Y-127165D02*
X379140D01*
X378740Y-127565D02*
Y-126765D01*
X375132Y-123610D02*
X375932D01*
X375532Y-124010D02*
Y-123210D01*
X314258Y-244775D02*
X315058D01*
X314658Y-245175D02*
Y-244375D01*
X314697Y-235081D02*
X315497D01*
X315097Y-235481D02*
Y-234681D01*
X314103Y-225180D02*
X314903D01*
X314503Y-225580D02*
Y-224780D01*
X288183Y-225590D02*
X288983D01*
X288583Y-225991D02*
Y-225190D01*
X287789Y-228740D02*
X288589D01*
X288189Y-229140D02*
Y-228340D01*
X287789Y-231102D02*
X288589D01*
X288189Y-231502D02*
Y-230702D01*
X287657Y-233478D02*
X288457D01*
X288057Y-233878D02*
Y-233078D01*
X287657Y-245095D02*
X288457D01*
X288057Y-245495D02*
Y-244695D01*
X287789Y-247638D02*
X288589D01*
X288189Y-248038D02*
Y-247238D01*
X287541Y-241819D02*
X288341D01*
X287941Y-242219D02*
Y-241419D01*
X287789Y-235827D02*
X288589D01*
X288189Y-236227D02*
Y-235427D01*
X588576Y-302756D02*
X589376D01*
X588976Y-303156D02*
Y-302356D01*
X579128Y-303150D02*
X579928D01*
X579528Y-303550D02*
Y-302750D01*
X615348Y-305512D02*
X616148D01*
X615748Y-305912D02*
Y-305112D01*
X562198Y-306693D02*
X562998D01*
X562598Y-307093D02*
Y-306293D01*
X376765Y-107283D02*
X377565D01*
X377165Y-107684D02*
Y-106884D01*
X383065Y-107480D02*
X383865D01*
X383465Y-107880D02*
Y-107080D01*
X346811Y-89891D02*
X349611D01*
X348211Y-91291D02*
Y-88491D01*
X356398Y-89963D02*
X359198D01*
X357798Y-91363D02*
Y-88563D01*
X375190Y-127165D02*
X375991D01*
X375590Y-127565D02*
Y-126765D01*
X105899Y-263632D02*
X106699D01*
X106299Y-264032D02*
Y-263231D01*
X379939Y-107321D02*
X380739D01*
X380339Y-107721D02*
Y-106921D01*
X154324Y-389616D02*
X155124D01*
X154724Y-390016D02*
Y-389216D01*
X156293Y-389616D02*
X157093D01*
X156693Y-390016D02*
Y-389216D01*
X158261Y-389616D02*
X159061D01*
X158661Y-390016D02*
Y-389216D01*
X154324Y-386466D02*
X155124D01*
X154724Y-386866D02*
Y-386066D01*
X156293Y-386466D02*
X157093D01*
X156693Y-386866D02*
Y-386066D01*
X158261Y-386466D02*
X159061D01*
X158661Y-386866D02*
Y-386066D01*
X531096Y-262647D02*
X531896D01*
X531496Y-263047D02*
Y-262247D01*
X461411Y-310679D02*
X462211D01*
X461811Y-311079D02*
Y-310279D01*
X449600Y-293750D02*
X450400D01*
X450000Y-294150D02*
Y-293350D01*
X422041Y-293789D02*
X422841D01*
X422441Y-294189D02*
Y-293389D01*
X531096Y-213435D02*
X531896D01*
X531496Y-213835D02*
Y-213035D01*
X338125Y-243567D02*
X338925D01*
X338525Y-243967D02*
Y-243167D01*
X525191Y-233088D02*
X525991D01*
X525591Y-233488D02*
Y-232688D01*
X439297Y-162549D02*
X440097D01*
X439697Y-162949D02*
Y-162149D01*
X342744Y-225173D02*
X343544D01*
X343144Y-225573D02*
Y-224773D01*
X420269Y-157923D02*
X421069D01*
X420669Y-158323D02*
Y-157523D01*
X531096Y-223277D02*
X531896D01*
X531496Y-223677D02*
Y-222877D01*
X338183Y-235236D02*
X338983D01*
X338583Y-235636D02*
Y-234836D01*
X525191Y-242962D02*
X525991D01*
X525591Y-243362D02*
Y-242562D01*
X429750Y-162253D02*
X430550D01*
X430150Y-162654D02*
Y-161854D01*
X343044Y-215373D02*
X343844D01*
X343444Y-215773D02*
Y-214973D01*
X431883Y-293750D02*
X432684D01*
X432283Y-294150D02*
Y-293350D01*
X410128Y-157923D02*
X410928D01*
X410528Y-158323D02*
Y-157523D01*
X342544Y-264473D02*
X343344D01*
X342944Y-264873D02*
Y-264073D01*
X443694Y-293750D02*
X444494D01*
X444095Y-294150D02*
Y-293350D01*
X422435Y-311072D02*
X423235D01*
X422835Y-311472D02*
Y-310672D01*
X531096Y-233088D02*
X531896D01*
X531496Y-233488D02*
Y-232688D01*
X429750Y-157923D02*
X430550D01*
X430150Y-158323D02*
Y-157523D01*
X338044Y-225173D02*
X338844D01*
X338444Y-225573D02*
Y-224773D01*
X402356Y-311072D02*
X403156D01*
X402756Y-311472D02*
Y-310672D01*
X525191Y-253969D02*
X525991D01*
X525591Y-254368D02*
Y-253569D01*
X419679Y-162549D02*
X420479D01*
X420079Y-162949D02*
Y-162149D01*
X343003Y-205651D02*
X343803D01*
X343403Y-206051D02*
Y-205251D01*
X525191Y-203592D02*
X525991D01*
X525591Y-203992D02*
Y-203192D01*
X399895Y-157824D02*
X400695D01*
X400295Y-158224D02*
Y-157424D01*
X342744Y-254773D02*
X343544D01*
X343144Y-255173D02*
Y-254373D01*
X431528Y-311189D02*
X432328D01*
X431928Y-311589D02*
Y-310789D01*
X531096Y-242962D02*
X531896D01*
X531496Y-243362D02*
Y-242562D01*
X338444Y-215273D02*
X339244D01*
X338844Y-215673D02*
Y-214873D01*
X401962Y-293750D02*
X402762D01*
X402362Y-294150D02*
Y-293350D01*
X525191Y-262647D02*
X525991D01*
X525591Y-263047D02*
Y-262247D01*
X410513Y-162758D02*
X411313D01*
X410913Y-163157D02*
Y-162357D01*
X338044Y-264473D02*
X338844D01*
X338444Y-264873D02*
Y-264073D01*
X455899Y-293750D02*
X456699D01*
X456299Y-294150D02*
Y-293350D01*
X437395Y-293750D02*
X438195D01*
X437795Y-294150D02*
Y-293350D01*
X525191Y-213435D02*
X525991D01*
X525591Y-213835D02*
Y-213035D01*
X458919Y-162510D02*
X459719D01*
X459319Y-162910D02*
Y-162110D01*
X458919Y-157922D02*
X459719D01*
X459319Y-158322D02*
Y-157522D01*
X342344Y-243747D02*
X343144D01*
X342744Y-244147D02*
Y-243347D01*
X412198Y-311072D02*
X412998D01*
X412598Y-311472D02*
Y-310672D01*
X531096Y-253969D02*
X531896D01*
X531496Y-254368D02*
Y-253569D01*
X449403Y-157923D02*
X450203D01*
X449803Y-158323D02*
Y-157523D01*
X338344Y-205473D02*
X339144D01*
X338744Y-205873D02*
Y-205073D01*
X531096Y-203592D02*
X531896D01*
X531496Y-203992D02*
Y-203192D01*
X400879Y-162509D02*
X401680D01*
X401279Y-162909D02*
Y-162109D01*
X439561Y-157923D02*
X440361D01*
X439961Y-158323D02*
Y-157523D01*
X338044Y-254773D02*
X338844D01*
X338444Y-255173D02*
Y-254373D01*
X461017Y-293750D02*
X461817D01*
X461417Y-294150D02*
Y-293350D01*
X525191Y-223277D02*
X525991D01*
X525591Y-223677D02*
Y-222877D01*
X449108Y-162549D02*
X449908D01*
X449508Y-162949D02*
Y-162149D01*
X343104Y-235236D02*
X343904D01*
X343504Y-235636D02*
Y-234836D01*
X411805Y-293750D02*
X412605D01*
X412205Y-294150D02*
Y-293350D01*
X639350Y-314581D02*
X640150D01*
X639750Y-314981D02*
Y-314181D01*
X658247Y-314581D02*
X659047D01*
X658647Y-314981D02*
Y-314181D01*
X509005Y-345138D02*
X509805D01*
X509405Y-345538D02*
Y-344738D01*
X508611Y-330177D02*
X509411D01*
X509011Y-330577D02*
Y-329777D01*
X56041Y-143600D02*
X56841D01*
X56441Y-144000D02*
Y-143200D01*
X56041Y-151600D02*
X56841D01*
X56441Y-152000D02*
Y-151200D01*
X56041Y-191600D02*
X56841D01*
X56441Y-192000D02*
Y-191200D01*
X56041Y-199600D02*
X56841D01*
X56441Y-200000D02*
Y-199200D01*
X56041Y-215600D02*
X56841D01*
X56441Y-216000D02*
Y-215200D01*
X56041Y-223600D02*
X56841D01*
X56441Y-224000D02*
Y-223200D01*
X56041Y-231600D02*
X56841D01*
X56441Y-232000D02*
Y-231200D01*
X56041Y-247600D02*
X56841D01*
X56441Y-248000D02*
Y-247200D01*
X56041Y-255600D02*
X56841D01*
X56441Y-256000D02*
Y-255200D01*
X56041Y-271600D02*
X56841D01*
X56441Y-272000D02*
Y-271200D01*
X56041Y-279600D02*
X56841D01*
X56441Y-280000D02*
Y-279200D01*
X56041Y-287600D02*
X56841D01*
X56441Y-288000D02*
Y-287200D01*
X56041Y-303600D02*
X56841D01*
X56441Y-304000D02*
Y-303200D01*
X56041Y-311600D02*
X56841D01*
X56441Y-312000D02*
Y-311200D01*
X56041Y-327600D02*
X56841D01*
X56441Y-328000D02*
Y-327200D01*
X56041Y-335600D02*
X56841D01*
X56441Y-336000D02*
Y-335200D01*
X56041Y-343600D02*
X56841D01*
X56441Y-344000D02*
Y-343200D01*
X56041Y-351600D02*
X56841D01*
X56441Y-352000D02*
Y-351200D01*
X54041Y-139600D02*
X54841D01*
X54441Y-140000D02*
Y-139200D01*
X52041Y-143600D02*
X52841D01*
X52441Y-144000D02*
Y-143200D01*
X54041Y-147600D02*
X54841D01*
X54441Y-148000D02*
Y-147200D01*
X52041Y-151600D02*
X52841D01*
X52441Y-152000D02*
Y-151200D01*
X52041Y-191600D02*
X52841D01*
X52441Y-192000D02*
Y-191200D01*
X54041Y-195600D02*
X54841D01*
X54441Y-196000D02*
Y-195200D01*
X52041Y-199600D02*
X52841D01*
X52441Y-200000D02*
Y-199200D01*
X54041Y-203600D02*
X54841D01*
X54441Y-204000D02*
Y-203200D01*
X52041Y-215600D02*
X52841D01*
X52441Y-216000D02*
Y-215200D01*
X54041Y-219600D02*
X54841D01*
X54441Y-220000D02*
Y-219200D01*
X52041Y-223600D02*
X52841D01*
X52441Y-224000D02*
Y-223200D01*
X54041Y-227600D02*
X54841D01*
X54441Y-228000D02*
Y-227200D01*
X52041Y-231600D02*
X52841D01*
X52441Y-232000D02*
Y-231200D01*
X54041Y-235600D02*
X54841D01*
X54441Y-236000D02*
Y-235200D01*
X54041Y-243600D02*
X54841D01*
X54441Y-244000D02*
Y-243200D01*
X52041Y-247600D02*
X52841D01*
X52441Y-248000D02*
Y-247200D01*
X54041Y-251600D02*
X54841D01*
X54441Y-252000D02*
Y-251200D01*
X52041Y-255600D02*
X52841D01*
X52441Y-256000D02*
Y-255200D01*
X54041Y-267600D02*
X54841D01*
X54441Y-268000D02*
Y-267200D01*
X52041Y-271600D02*
X52841D01*
X52441Y-272000D02*
Y-271200D01*
X54041Y-275600D02*
X54841D01*
X54441Y-276000D02*
Y-275200D01*
X52041Y-279600D02*
X52841D01*
X52441Y-280000D02*
Y-279200D01*
X52041Y-287600D02*
X52841D01*
X52441Y-288000D02*
Y-287200D01*
X54041Y-291600D02*
X54841D01*
X54441Y-292000D02*
Y-291200D01*
X54041Y-299600D02*
X54841D01*
X54441Y-300000D02*
Y-299200D01*
X52041Y-303600D02*
X52841D01*
X52441Y-304000D02*
Y-303200D01*
X54041Y-307600D02*
X54841D01*
X54441Y-308000D02*
Y-307200D01*
X52041Y-311600D02*
X52841D01*
X52441Y-312000D02*
Y-311200D01*
X54041Y-323600D02*
X54841D01*
X54441Y-324000D02*
Y-323200D01*
X52041Y-327600D02*
X52841D01*
X52441Y-328000D02*
Y-327200D01*
X54041Y-331600D02*
X54841D01*
X54441Y-332000D02*
Y-331200D01*
X52041Y-335600D02*
X52841D01*
X52441Y-336000D02*
Y-335200D01*
X54041Y-339600D02*
X54841D01*
X54441Y-340000D02*
Y-339200D01*
X52041Y-343600D02*
X52841D01*
X52441Y-344000D02*
Y-343200D01*
X52041Y-351600D02*
X52841D01*
X52441Y-352000D02*
Y-351200D01*
X50041Y-139600D02*
X50841D01*
X50441Y-140000D02*
Y-139200D01*
X48041Y-143600D02*
X48841D01*
X48441Y-144000D02*
Y-143200D01*
X50041Y-195600D02*
X50841D01*
X50441Y-196000D02*
Y-195200D01*
X48041Y-199600D02*
X48841D01*
X48441Y-200000D02*
Y-199200D01*
X48041Y-223600D02*
X48841D01*
X48441Y-224000D02*
Y-223200D01*
X50041Y-227600D02*
X50841D01*
X50441Y-228000D02*
Y-227200D01*
X48041Y-231600D02*
X48841D01*
X48441Y-232000D02*
Y-231200D01*
X50041Y-235600D02*
X50841D01*
X50441Y-236000D02*
Y-235200D01*
X50041Y-243600D02*
X50841D01*
X50441Y-244000D02*
Y-243200D01*
X48041Y-247600D02*
X48841D01*
X48441Y-248000D02*
Y-247200D01*
X50041Y-251600D02*
X50841D01*
X50441Y-252000D02*
Y-251200D01*
X50041Y-275600D02*
X50841D01*
X50441Y-276000D02*
Y-275200D01*
X48041Y-279600D02*
X48841D01*
X48441Y-280000D02*
Y-279200D01*
X48041Y-287600D02*
X48841D01*
X48441Y-288000D02*
Y-287200D01*
X50041Y-291600D02*
X50841D01*
X50441Y-292000D02*
Y-291200D01*
X50041Y-299600D02*
X50841D01*
X50441Y-300000D02*
Y-299200D01*
X48041Y-303600D02*
X48841D01*
X48441Y-304000D02*
Y-303200D01*
X50041Y-331600D02*
X50841D01*
X50441Y-332000D02*
Y-331200D01*
X48041Y-335600D02*
X48841D01*
X48441Y-336000D02*
Y-335200D01*
X50041Y-339600D02*
X50841D01*
X50441Y-340000D02*
Y-339200D01*
X48041Y-343600D02*
X48841D01*
X48441Y-344000D02*
Y-343200D01*
X48041Y-351600D02*
X48841D01*
X48441Y-352000D02*
Y-351200D01*
X46041Y-139600D02*
X46841D01*
X46441Y-140000D02*
Y-139200D01*
X44041Y-143600D02*
X44841D01*
X44441Y-144000D02*
Y-143200D01*
X46041Y-227600D02*
X46841D01*
X46441Y-228000D02*
Y-227200D01*
X44041Y-231600D02*
X44841D01*
X44441Y-232000D02*
Y-231200D01*
X46041Y-235600D02*
X46841D01*
X46441Y-236000D02*
Y-235200D01*
X46041Y-243600D02*
X46841D01*
X46441Y-244000D02*
Y-243200D01*
X44041Y-247600D02*
X44841D01*
X44441Y-248000D02*
Y-247200D01*
X44041Y-279600D02*
X44841D01*
X44441Y-280000D02*
Y-279200D01*
X44041Y-287600D02*
X44841D01*
X44441Y-288000D02*
Y-287200D01*
X46041Y-291600D02*
X46841D01*
X46441Y-292000D02*
Y-291200D01*
X46041Y-299600D02*
X46841D01*
X46441Y-300000D02*
Y-299200D01*
X46041Y-331600D02*
X46841D01*
X46441Y-332000D02*
Y-331200D01*
X44041Y-335600D02*
X44841D01*
X44441Y-336000D02*
Y-335200D01*
X46041Y-339600D02*
X46841D01*
X46441Y-340000D02*
Y-339200D01*
X44041Y-343600D02*
X44841D01*
X44441Y-344000D02*
Y-343200D01*
X44041Y-351600D02*
X44841D01*
X44441Y-352000D02*
Y-351200D01*
X42041Y-139600D02*
X42841D01*
X42441Y-140000D02*
Y-139200D01*
X40041Y-143600D02*
X40841D01*
X40441Y-144000D02*
Y-143200D01*
X40041Y-223600D02*
X40841D01*
X40441Y-224000D02*
Y-223200D01*
X42041Y-227600D02*
X42841D01*
X42441Y-228000D02*
Y-227200D01*
X40041Y-231600D02*
X40841D01*
X40441Y-232000D02*
Y-231200D01*
X42041Y-235600D02*
X42841D01*
X42441Y-236000D02*
Y-235200D01*
X42041Y-243600D02*
X42841D01*
X42441Y-244000D02*
Y-243200D01*
X40041Y-247600D02*
X40841D01*
X40441Y-248000D02*
Y-247200D01*
X42041Y-299600D02*
X42841D01*
X42441Y-300000D02*
Y-299200D01*
X42041Y-331600D02*
X42841D01*
X42441Y-332000D02*
Y-331200D01*
X40041Y-335600D02*
X40841D01*
X40441Y-336000D02*
Y-335200D01*
X42041Y-339600D02*
X42841D01*
X42441Y-340000D02*
Y-339200D01*
X40041Y-343600D02*
X40841D01*
X40441Y-344000D02*
Y-343200D01*
X40041Y-351600D02*
X40841D01*
X40441Y-352000D02*
Y-351200D01*
X38041Y-139600D02*
X38841D01*
X38441Y-140000D02*
Y-139200D01*
X36041Y-143600D02*
X36841D01*
X36441Y-144000D02*
Y-143200D01*
X36041Y-151600D02*
X36841D01*
X36441Y-152000D02*
Y-151200D01*
X36041Y-215600D02*
X36841D01*
X36441Y-216000D02*
Y-215200D01*
X36041Y-223600D02*
X36841D01*
X36441Y-224000D02*
Y-223200D01*
X38041Y-227600D02*
X38841D01*
X38441Y-228000D02*
Y-227200D01*
X36041Y-231600D02*
X36841D01*
X36441Y-232000D02*
Y-231200D01*
X38041Y-235600D02*
X38841D01*
X38441Y-236000D02*
Y-235200D01*
X38041Y-243600D02*
X38841D01*
X38441Y-244000D02*
Y-243200D01*
X36041Y-247600D02*
X36841D01*
X36441Y-248000D02*
Y-247200D01*
X38041Y-251600D02*
X38841D01*
X38441Y-252000D02*
Y-251200D01*
X36041Y-255600D02*
X36841D01*
X36441Y-256000D02*
Y-255200D01*
X36041Y-327600D02*
X36841D01*
X36441Y-328000D02*
Y-327200D01*
X38041Y-331600D02*
X38841D01*
X38441Y-332000D02*
Y-331200D01*
X36041Y-335600D02*
X36841D01*
X36441Y-336000D02*
Y-335200D01*
X38041Y-339600D02*
X38841D01*
X38441Y-340000D02*
Y-339200D01*
X36041Y-343600D02*
X36841D01*
X36441Y-344000D02*
Y-343200D01*
X36041Y-351600D02*
X36841D01*
X36441Y-352000D02*
Y-351200D01*
X34041Y-139600D02*
X34841D01*
X34441Y-140000D02*
Y-139200D01*
X32041Y-143600D02*
X32841D01*
X32441Y-144000D02*
Y-143200D01*
X34041Y-147600D02*
X34841D01*
X34441Y-148000D02*
Y-147200D01*
X32041Y-151600D02*
X32841D01*
X32441Y-152000D02*
Y-151200D01*
X34041Y-163600D02*
X34841D01*
X34441Y-164000D02*
Y-163200D01*
X34041Y-219600D02*
X34841D01*
X34441Y-220000D02*
Y-219200D01*
X34041Y-227600D02*
X34841D01*
X34441Y-228000D02*
Y-227200D01*
X34041Y-235600D02*
X34841D01*
X34441Y-236000D02*
Y-235200D01*
X34041Y-243600D02*
X34841D01*
X34441Y-244000D02*
Y-243200D01*
X34041Y-251600D02*
X34841D01*
X34441Y-252000D02*
Y-251200D01*
X34041Y-267600D02*
X34841D01*
X34441Y-268000D02*
Y-267200D01*
X34041Y-275600D02*
X34841D01*
X34441Y-276000D02*
Y-275200D01*
X34041Y-299600D02*
X34841D01*
X34441Y-300000D02*
Y-299200D01*
X34041Y-307600D02*
X34841D01*
X34441Y-308000D02*
Y-307200D01*
X34041Y-323600D02*
X34841D01*
X34441Y-324000D02*
Y-323200D01*
X32041Y-327600D02*
X32841D01*
X32441Y-328000D02*
Y-327200D01*
X34041Y-331600D02*
X34841D01*
X34441Y-332000D02*
Y-331200D01*
X32041Y-335600D02*
X32841D01*
X32441Y-336000D02*
Y-335200D01*
X34041Y-339600D02*
X34841D01*
X34441Y-340000D02*
Y-339200D01*
X32041Y-343600D02*
X32841D01*
X32441Y-344000D02*
Y-343200D01*
X32041Y-351600D02*
X32841D01*
X32441Y-352000D02*
Y-351200D01*
X30041Y-139600D02*
X30841D01*
X30441Y-140000D02*
Y-139200D01*
X28041Y-143600D02*
X28841D01*
X28441Y-144000D02*
Y-143200D01*
X30041Y-147600D02*
X30841D01*
X30441Y-148000D02*
Y-147200D01*
X28041Y-151600D02*
X28841D01*
X28441Y-152000D02*
Y-151200D01*
X30041Y-163600D02*
X30841D01*
X30441Y-164000D02*
Y-163200D01*
X28041Y-167600D02*
X28841D01*
X28441Y-168000D02*
Y-167200D01*
X28041Y-327600D02*
X28841D01*
X28441Y-328000D02*
Y-327200D01*
X30041Y-331600D02*
X30841D01*
X30441Y-332000D02*
Y-331200D01*
X28041Y-335600D02*
X28841D01*
X28441Y-336000D02*
Y-335200D01*
X30041Y-339600D02*
X30841D01*
X30441Y-340000D02*
Y-339200D01*
X28041Y-343600D02*
X28841D01*
X28441Y-344000D02*
Y-343200D01*
X28041Y-351600D02*
X28841D01*
X28441Y-352000D02*
Y-351200D01*
X26041Y-139600D02*
X26841D01*
X26441Y-140000D02*
Y-139200D01*
X24041Y-143600D02*
X24841D01*
X24441Y-144000D02*
Y-143200D01*
X26041Y-147600D02*
X26841D01*
X26441Y-148000D02*
Y-147200D01*
X24041Y-151600D02*
X24841D01*
X24441Y-152000D02*
Y-151200D01*
X26041Y-163600D02*
X26841D01*
X26441Y-164000D02*
Y-163200D01*
X24041Y-167600D02*
X24841D01*
X24441Y-168000D02*
Y-167200D01*
X24041Y-191600D02*
X24841D01*
X24441Y-192000D02*
Y-191200D01*
X26041Y-195600D02*
X26841D01*
X26441Y-196000D02*
Y-195200D01*
X24041Y-287600D02*
X24841D01*
X24441Y-288000D02*
Y-287200D01*
X26041Y-299600D02*
X26841D01*
X26441Y-300000D02*
Y-299200D01*
X24041Y-303600D02*
X24841D01*
X24441Y-304000D02*
Y-303200D01*
X26041Y-307600D02*
X26841D01*
X26441Y-308000D02*
Y-307200D01*
X24041Y-311600D02*
X24841D01*
X24441Y-312000D02*
Y-311200D01*
X26041Y-331600D02*
X26841D01*
X26441Y-332000D02*
Y-331200D01*
X24041Y-335600D02*
X24841D01*
X24441Y-336000D02*
Y-335200D01*
X26041Y-339600D02*
X26841D01*
X26441Y-340000D02*
Y-339200D01*
X24041Y-343600D02*
X24841D01*
X24441Y-344000D02*
Y-343200D01*
X24041Y-351600D02*
X24841D01*
X24441Y-352000D02*
Y-351200D01*
X22041Y-139600D02*
X22841D01*
X22441Y-140000D02*
Y-139200D01*
X20041Y-143600D02*
X20841D01*
X20441Y-144000D02*
Y-143200D01*
X22041Y-147600D02*
X22841D01*
X22441Y-148000D02*
Y-147200D01*
X20041Y-151600D02*
X20841D01*
X20441Y-152000D02*
Y-151200D01*
X22041Y-163600D02*
X22841D01*
X22441Y-164000D02*
Y-163200D01*
X20041Y-167600D02*
X20841D01*
X20441Y-168000D02*
Y-167200D01*
X22041Y-171600D02*
X22841D01*
X22441Y-172000D02*
Y-171200D01*
X20041Y-191600D02*
X20841D01*
X20441Y-192000D02*
Y-191200D01*
X22041Y-195600D02*
X22841D01*
X22441Y-196000D02*
Y-195200D01*
X20041Y-199600D02*
X20841D01*
X20441Y-200000D02*
Y-199200D01*
X20041Y-231600D02*
X20841D01*
X20441Y-232000D02*
Y-231200D01*
X22041Y-235600D02*
X22841D01*
X22441Y-236000D02*
Y-235200D01*
X22041Y-243600D02*
X22841D01*
X22441Y-244000D02*
Y-243200D01*
X20041Y-247600D02*
X20841D01*
X20441Y-248000D02*
Y-247200D01*
X22041Y-251600D02*
X22841D01*
X22441Y-252000D02*
Y-251200D01*
X20041Y-255600D02*
X20841D01*
X20441Y-256000D02*
Y-255200D01*
X22041Y-259600D02*
X22841D01*
X22441Y-260000D02*
Y-259200D01*
X22041Y-267600D02*
X22841D01*
X22441Y-268000D02*
Y-267200D01*
X20041Y-271600D02*
X20841D01*
X20441Y-272000D02*
Y-271200D01*
X22041Y-283600D02*
X22841D01*
X22441Y-284000D02*
Y-283200D01*
X20041Y-287600D02*
X20841D01*
X20441Y-288000D02*
Y-287200D01*
X22041Y-291600D02*
X22841D01*
X22441Y-292000D02*
Y-291200D01*
X22041Y-299600D02*
X22841D01*
X22441Y-300000D02*
Y-299200D01*
X20041Y-303600D02*
X20841D01*
X20441Y-304000D02*
Y-303200D01*
X22041Y-307600D02*
X22841D01*
X22441Y-308000D02*
Y-307200D01*
X20041Y-311600D02*
X20841D01*
X20441Y-312000D02*
Y-311200D01*
X22041Y-323600D02*
X22841D01*
X22441Y-324000D02*
Y-323200D01*
X20041Y-335600D02*
X20841D01*
X20441Y-336000D02*
Y-335200D01*
X22041Y-339600D02*
X22841D01*
X22441Y-340000D02*
Y-339200D01*
X20041Y-343600D02*
X20841D01*
X20441Y-344000D02*
Y-343200D01*
X20041Y-351600D02*
X20841D01*
X20441Y-352000D02*
Y-351200D01*
X18041Y-139600D02*
X18841D01*
X18441Y-140000D02*
Y-139200D01*
X16041Y-143600D02*
X16841D01*
X16441Y-144000D02*
Y-143200D01*
X18041Y-147600D02*
X18841D01*
X18441Y-148000D02*
Y-147200D01*
X16041Y-151600D02*
X16841D01*
X16441Y-152000D02*
Y-151200D01*
X18041Y-163600D02*
X18841D01*
X18441Y-164000D02*
Y-163200D01*
X16041Y-167600D02*
X16841D01*
X16441Y-168000D02*
Y-167200D01*
X18041Y-171600D02*
X18841D01*
X18441Y-172000D02*
Y-171200D01*
X16041Y-191600D02*
X16841D01*
X16441Y-192000D02*
Y-191200D01*
X18041Y-195600D02*
X18841D01*
X18441Y-196000D02*
Y-195200D01*
X16041Y-199600D02*
X16841D01*
X16441Y-200000D02*
Y-199200D01*
X18041Y-203600D02*
X18841D01*
X18441Y-204000D02*
Y-203200D01*
X16041Y-215600D02*
X16841D01*
X16441Y-216000D02*
Y-215200D01*
X18041Y-219600D02*
X18841D01*
X18441Y-220000D02*
Y-219200D01*
X16041Y-223600D02*
X16841D01*
X16441Y-224000D02*
Y-223200D01*
X18041Y-235600D02*
X18841D01*
X18441Y-236000D02*
Y-235200D01*
X18041Y-243600D02*
X18841D01*
X18441Y-244000D02*
Y-243200D01*
X16041Y-247600D02*
X16841D01*
X16441Y-248000D02*
Y-247200D01*
X18041Y-251600D02*
X18841D01*
X18441Y-252000D02*
Y-251200D01*
X16041Y-255600D02*
X16841D01*
X16441Y-256000D02*
Y-255200D01*
X18041Y-259600D02*
X18841D01*
X18441Y-260000D02*
Y-259200D01*
X18041Y-267600D02*
X18841D01*
X18441Y-268000D02*
Y-267200D01*
X16041Y-271600D02*
X16841D01*
X16441Y-272000D02*
Y-271200D01*
X18041Y-275600D02*
X18841D01*
X18441Y-276000D02*
Y-275200D01*
X16041Y-279600D02*
X16841D01*
X16441Y-280000D02*
Y-279200D01*
X18041Y-291600D02*
X18841D01*
X18441Y-292000D02*
Y-291200D01*
X18041Y-299600D02*
X18841D01*
X18441Y-300000D02*
Y-299200D01*
X16041Y-303600D02*
X16841D01*
X16441Y-304000D02*
Y-303200D01*
X18041Y-307600D02*
X18841D01*
X18441Y-308000D02*
Y-307200D01*
X16041Y-311600D02*
X16841D01*
X16441Y-312000D02*
Y-311200D01*
X18041Y-323600D02*
X18841D01*
X18441Y-324000D02*
Y-323200D01*
X16041Y-327600D02*
X16841D01*
X16441Y-328000D02*
Y-327200D01*
X18041Y-339600D02*
X18841D01*
X18441Y-340000D02*
Y-339200D01*
X16041Y-343600D02*
X16841D01*
X16441Y-344000D02*
Y-343200D01*
X16041Y-351600D02*
X16841D01*
X16441Y-352000D02*
Y-351200D01*
X14041Y-139600D02*
X14841D01*
X14441Y-140000D02*
Y-139200D01*
X12041Y-143600D02*
X12841D01*
X12441Y-144000D02*
Y-143200D01*
X14041Y-147600D02*
X14841D01*
X14441Y-148000D02*
Y-147200D01*
X12041Y-151600D02*
X12841D01*
X12441Y-152000D02*
Y-151200D01*
X14041Y-163600D02*
X14841D01*
X14441Y-164000D02*
Y-163200D01*
X12041Y-167600D02*
X12841D01*
X12441Y-168000D02*
Y-167200D01*
X14041Y-171600D02*
X14841D01*
X14441Y-172000D02*
Y-171200D01*
X12041Y-191600D02*
X12841D01*
X12441Y-192000D02*
Y-191200D01*
X14041Y-195600D02*
X14841D01*
X14441Y-196000D02*
Y-195200D01*
X12041Y-199600D02*
X12841D01*
X12441Y-200000D02*
Y-199200D01*
X14041Y-203600D02*
X14841D01*
X14441Y-204000D02*
Y-203200D01*
X12041Y-215600D02*
X12841D01*
X12441Y-216000D02*
Y-215200D01*
X14041Y-219600D02*
X14841D01*
X14441Y-220000D02*
Y-219200D01*
X12041Y-223600D02*
X12841D01*
X12441Y-224000D02*
Y-223200D01*
X14041Y-243600D02*
X14841D01*
X14441Y-244000D02*
Y-243200D01*
X12041Y-247600D02*
X12841D01*
X12441Y-248000D02*
Y-247200D01*
X14041Y-251600D02*
X14841D01*
X14441Y-252000D02*
Y-251200D01*
X12041Y-255600D02*
X12841D01*
X12441Y-256000D02*
Y-255200D01*
X14041Y-259600D02*
X14841D01*
X14441Y-260000D02*
Y-259200D01*
X14041Y-267600D02*
X14841D01*
X14441Y-268000D02*
Y-267200D01*
X12041Y-271600D02*
X12841D01*
X12441Y-272000D02*
Y-271200D01*
X14041Y-275600D02*
X14841D01*
X14441Y-276000D02*
Y-275200D01*
X12041Y-279600D02*
X12841D01*
X12441Y-280000D02*
Y-279200D01*
X14041Y-291600D02*
X14841D01*
X14441Y-292000D02*
Y-291200D01*
X14041Y-299600D02*
X14841D01*
X14441Y-300000D02*
Y-299200D01*
X12041Y-303600D02*
X12841D01*
X12441Y-304000D02*
Y-303200D01*
X14041Y-307600D02*
X14841D01*
X14441Y-308000D02*
Y-307200D01*
X12041Y-311600D02*
X12841D01*
X12441Y-312000D02*
Y-311200D01*
X14041Y-323600D02*
X14841D01*
X14441Y-324000D02*
Y-323200D01*
X12041Y-327600D02*
X12841D01*
X12441Y-328000D02*
Y-327200D01*
X14041Y-331600D02*
X14841D01*
X14441Y-332000D02*
Y-331200D01*
X12041Y-343600D02*
X12841D01*
X12441Y-344000D02*
Y-343200D01*
X12041Y-351600D02*
X12841D01*
X12441Y-352000D02*
Y-351200D01*
X10041Y-139600D02*
X10841D01*
X10441Y-140000D02*
Y-139200D01*
X10041Y-163600D02*
X10841D01*
X10441Y-164000D02*
Y-163200D01*
X10041Y-171600D02*
X10841D01*
X10441Y-172000D02*
Y-171200D01*
X8041Y-191600D02*
X8841D01*
X8441Y-192000D02*
Y-191200D01*
X10041Y-195600D02*
X10841D01*
X10441Y-196000D02*
Y-195200D01*
X10041Y-203600D02*
X10841D01*
X10441Y-204000D02*
Y-203200D01*
X10041Y-227600D02*
X10841D01*
X10441Y-228000D02*
Y-227200D01*
X10041Y-243600D02*
X10841D01*
X10441Y-244000D02*
Y-243200D01*
X8041Y-247600D02*
X8841D01*
X8441Y-248000D02*
Y-247200D01*
X10041Y-251600D02*
X10841D01*
X10441Y-252000D02*
Y-251200D01*
X10041Y-259600D02*
X10841D01*
X10441Y-260000D02*
Y-259200D01*
X10041Y-267600D02*
X10841D01*
X10441Y-268000D02*
Y-267200D01*
X10041Y-275600D02*
X10841D01*
X10441Y-276000D02*
Y-275200D01*
X8041Y-279600D02*
X8841D01*
X8441Y-280000D02*
Y-279200D01*
X10041Y-299600D02*
X10841D01*
X10441Y-300000D02*
Y-299200D01*
X10041Y-323600D02*
X10841D01*
X10441Y-324000D02*
Y-323200D01*
X10041Y-331600D02*
X10841D01*
X10441Y-332000D02*
Y-331200D01*
X8041Y-351600D02*
X8841D01*
X8441Y-352000D02*
Y-351200D01*
X6041Y-139600D02*
X6841D01*
X6441Y-140000D02*
Y-139200D01*
X4041Y-191600D02*
X4841D01*
X4441Y-192000D02*
Y-191200D01*
X6041Y-243600D02*
X6841D01*
X6441Y-244000D02*
Y-243200D01*
X4041Y-351600D02*
X4841D01*
X4441Y-352000D02*
Y-351200D01*
X2041Y-243600D02*
X2841D01*
X2441Y-244000D02*
Y-243200D01*
X41Y-351600D02*
X841D01*
X441Y-352000D02*
Y-351200D01*
X-3959Y-191600D02*
X-3159D01*
X-3559Y-192000D02*
Y-191200D01*
X-1959Y-243600D02*
X-1159D01*
X-1559Y-244000D02*
Y-243200D01*
X-3959Y-351600D02*
X-3159D01*
X-3559Y-352000D02*
Y-351200D01*
X-5959Y-139600D02*
X-5159D01*
X-5559Y-140000D02*
Y-139200D01*
X-7959Y-143600D02*
X-7159D01*
X-7559Y-144000D02*
Y-143200D01*
X-7959Y-167600D02*
X-7159D01*
X-7559Y-168000D02*
Y-167200D01*
X-7959Y-191600D02*
X-7159D01*
X-7559Y-192000D02*
Y-191200D01*
X-7959Y-199600D02*
X-7159D01*
X-7559Y-200000D02*
Y-199200D01*
X-7959Y-223600D02*
X-7159D01*
X-7559Y-224000D02*
Y-223200D01*
X-5959Y-227600D02*
X-5159D01*
X-5559Y-228000D02*
Y-227200D01*
X-5959Y-243600D02*
X-5159D01*
X-5559Y-244000D02*
Y-243200D01*
X-7959Y-247600D02*
X-7159D01*
X-7559Y-248000D02*
Y-247200D01*
X-7959Y-279600D02*
X-7159D01*
X-7559Y-280000D02*
Y-279200D01*
X-5959Y-299600D02*
X-5159D01*
X-5559Y-300000D02*
Y-299200D01*
X-7959Y-303600D02*
X-7159D01*
X-7559Y-304000D02*
Y-303200D01*
X-7959Y-327600D02*
X-7159D01*
X-7559Y-328000D02*
Y-327200D01*
X-7959Y-351600D02*
X-7159D01*
X-7559Y-352000D02*
Y-351200D01*
X-9959Y-139600D02*
X-9159D01*
X-9559Y-140000D02*
Y-139200D01*
X-9959Y-171600D02*
X-9159D01*
X-9559Y-172000D02*
Y-171200D01*
X-11959Y-191600D02*
X-11159D01*
X-11559Y-192000D02*
Y-191200D01*
X-9959Y-195600D02*
X-9159D01*
X-9559Y-196000D02*
Y-195200D01*
X-9959Y-227600D02*
X-9159D01*
X-9559Y-228000D02*
Y-227200D01*
X-9959Y-243600D02*
X-9159D01*
X-9559Y-244000D02*
Y-243200D01*
X-11959Y-247600D02*
X-11159D01*
X-11559Y-248000D02*
Y-247200D01*
X-9959Y-251600D02*
X-9159D01*
X-9559Y-252000D02*
Y-251200D01*
X-9959Y-275600D02*
X-9159D01*
X-9559Y-276000D02*
Y-275200D01*
X-11959Y-279600D02*
X-11159D01*
X-11559Y-280000D02*
Y-279200D01*
X-9959Y-299600D02*
X-9159D01*
X-9559Y-300000D02*
Y-299200D01*
X-9959Y-331600D02*
X-9159D01*
X-9559Y-332000D02*
Y-331200D01*
X-11959Y-351600D02*
X-11159D01*
X-11559Y-352000D02*
Y-351200D01*
X-13959Y-139600D02*
X-13159D01*
X-13559Y-140000D02*
Y-139200D01*
X-15959Y-191600D02*
X-15159D01*
X-15559Y-192000D02*
Y-191200D01*
X-13959Y-243600D02*
X-13159D01*
X-13559Y-244000D02*
Y-243200D01*
X-15959Y-351600D02*
X-15159D01*
X-15559Y-352000D02*
Y-351200D01*
X-19959Y-263600D02*
X-19159D01*
X-19559Y-264000D02*
Y-263200D01*
X-19959Y-351600D02*
X-19159D01*
X-19559Y-352000D02*
Y-351200D01*
X-23959Y-159600D02*
X-23159D01*
X-23559Y-160000D02*
Y-159200D01*
X-23959Y-191600D02*
X-23159D01*
X-23559Y-192000D02*
Y-191200D01*
X-21959Y-211600D02*
X-21159D01*
X-21559Y-212000D02*
Y-211200D01*
X-23959Y-263600D02*
X-23159D01*
X-23559Y-264000D02*
Y-263200D01*
X-21959Y-315600D02*
X-21159D01*
X-21559Y-316000D02*
Y-315200D01*
X-23959Y-351600D02*
X-23159D01*
X-23559Y-352000D02*
Y-351200D01*
X-25959Y-139600D02*
X-25159D01*
X-25559Y-140000D02*
Y-139200D01*
X-25959Y-155600D02*
X-25159D01*
X-25559Y-156000D02*
Y-155200D01*
X-25959Y-211600D02*
X-25159D01*
X-25559Y-212000D02*
Y-211200D01*
X-25959Y-259600D02*
X-25159D01*
X-25559Y-260000D02*
Y-259200D01*
X-25959Y-267600D02*
X-25159D01*
X-25559Y-268000D02*
Y-267200D01*
X-25959Y-299600D02*
X-25159D01*
X-25559Y-300000D02*
Y-299200D01*
X-25959Y-315600D02*
X-25159D01*
X-25559Y-316000D02*
Y-315200D01*
X233852Y-133742D02*
X234652D01*
X234252Y-134142D02*
Y-133342D01*
X263380Y-106151D02*
X264179D01*
X263779Y-106551D02*
Y-105751D01*
X71450Y-147638D02*
X72250D01*
X71850Y-148038D02*
Y-147238D01*
X75387Y-131890D02*
X76187D01*
X75787Y-132290D02*
Y-131490D01*
X622600Y-37402D02*
X623400D01*
X623000Y-37802D02*
Y-37002D01*
X609836Y-8858D02*
X610636D01*
X610236Y-9258D02*
Y-8458D01*
X608852Y-26575D02*
X609652D01*
X609252Y-26975D02*
Y-26175D01*
X98025Y-102362D02*
X98825D01*
X98425Y-102762D02*
Y-101962D01*
X89167Y-102362D02*
X89967D01*
X89567Y-102762D02*
Y-101962D01*
X85230Y-313976D02*
X86030D01*
X85630Y-314376D02*
Y-313576D01*
X86214Y-258858D02*
X87014D01*
X86614Y-259258D02*
Y-258458D01*
X81293Y-205709D02*
X82093D01*
X81693Y-206109D02*
Y-205309D01*
X359836Y-268586D02*
X360636D01*
X360236Y-268986D02*
Y-268186D01*
X359836Y-272490D02*
X360636D01*
X360236Y-272890D02*
Y-272090D01*
X63576Y-227362D02*
X64376D01*
X63976Y-227762D02*
Y-226962D01*
X68498Y-285433D02*
X69298D01*
X68898Y-285833D02*
Y-285033D01*
X67513Y-340551D02*
X68313D01*
X67913Y-340951D02*
Y-340151D01*
X68173Y-179321D02*
X68973D01*
X68573Y-179721D02*
Y-178921D01*
X43891Y-252953D02*
X44691D01*
X44291Y-253353D02*
Y-252553D01*
X43891Y-272638D02*
X44691D01*
X44291Y-273038D02*
Y-272238D01*
X43891Y-326772D02*
X44691D01*
X44291Y-327172D02*
Y-326372D01*
X43891Y-307087D02*
X44691D01*
X44291Y-307487D02*
Y-306687D01*
X26175Y-291339D02*
X26975D01*
X26575Y-291739D02*
Y-290939D01*
X31096Y-189961D02*
X31896D01*
X31496Y-190361D02*
Y-189561D01*
X43891Y-147638D02*
X44691D01*
X44291Y-148038D02*
Y-147238D01*
X43891Y-167323D02*
X44691D01*
X44291Y-167723D02*
Y-166923D01*
X43891Y-200787D02*
X44691D01*
X44291Y-201187D02*
Y-200387D01*
X43891Y-220472D02*
X44691D01*
X44291Y-220872D02*
Y-220072D01*
X325387Y-243205D02*
X326187D01*
X325787Y-243605D02*
Y-242805D01*
X325387Y-233362D02*
X326187D01*
X325787Y-233762D02*
Y-232962D01*
X103009Y-141732D02*
X103809D01*
X103409Y-142132D02*
Y-141332D01*
X102946Y-110236D02*
X103746D01*
X103347Y-110636D02*
Y-109836D01*
X118694Y-126047D02*
X119494D01*
X119095Y-126447D02*
Y-125647D01*
X518301Y-104214D02*
X519101D01*
X518701Y-104614D02*
Y-103814D01*
X519187Y-134596D02*
X519987D01*
X519587Y-134996D02*
Y-134196D01*
X528143Y-104214D02*
X528943D01*
X528543Y-104614D02*
Y-103814D01*
X658065Y-21899D02*
X658865D01*
X658465Y-22299D02*
Y-21499D01*
X624600Y-29773D02*
X625400D01*
X625000Y-30173D02*
Y-29373D01*
X113773Y-83088D02*
X114573D01*
X114173Y-83488D02*
Y-82688D01*
X441529Y-122883D02*
X442329D01*
X441929Y-123284D02*
Y-122484D01*
X129521Y-79576D02*
X130321D01*
X129921Y-79976D02*
Y-79176D01*
X162671Y-390730D02*
X163471D01*
X163071Y-391130D02*
Y-390330D01*
X99010Y-50049D02*
X99809D01*
X99410Y-50449D02*
Y-49649D01*
X26095Y-8991D02*
X26895D01*
X26495Y-9391D02*
Y-8591D01*
X512257Y-270462D02*
X513057D01*
X512657Y-270862D02*
Y-270062D01*
X258885Y-390247D02*
X259685D01*
X259285Y-390647D02*
Y-389847D01*
X266804Y-390009D02*
X267604D01*
X267204Y-390409D02*
Y-389610D01*
X215762Y-390947D02*
X216562D01*
X216162Y-391347D02*
Y-390547D01*
X234744Y-390416D02*
X235544D01*
X235144Y-390816D02*
Y-390016D01*
X251056Y-390009D02*
X251856D01*
X251456Y-390409D02*
Y-389610D01*
X225663Y-390722D02*
X226463D01*
X226063Y-391122D02*
Y-390322D01*
X280801Y-390009D02*
X281601D01*
X281201Y-390409D02*
Y-389610D01*
X174541Y-390600D02*
X175341D01*
X174941Y-391000D02*
Y-390200D01*
X202041Y-390600D02*
X202841D01*
X202441Y-391000D02*
Y-390200D01*
X543891Y-199655D02*
X544691D01*
X544291Y-200055D02*
Y-199255D01*
X509443Y-197687D02*
X510243D01*
X509842Y-198087D02*
Y-197287D01*
X543891Y-201624D02*
X544691D01*
X544291Y-202024D02*
Y-201224D01*
X509443Y-199655D02*
X510243D01*
X509842Y-200055D02*
Y-199255D01*
X509443Y-201624D02*
X510243D01*
X509842Y-202024D02*
Y-201224D01*
X543891Y-197687D02*
X544691D01*
X544291Y-198087D02*
Y-197287D01*
X509443Y-195718D02*
X510243D01*
X509842Y-196118D02*
Y-195318D01*
X361411Y-207087D02*
X362211D01*
X361811Y-207487D02*
Y-206687D01*
X361017Y-203150D02*
X361817D01*
X361417Y-203550D02*
Y-202750D01*
X326569Y-197573D02*
X327368D01*
X326969Y-197973D02*
Y-197173D01*
X326566Y-195171D02*
X327366D01*
X326966Y-195571D02*
Y-194771D01*
X366135Y-202362D02*
X366935D01*
X366535Y-202762D02*
Y-201962D01*
X358261Y-194488D02*
X359061D01*
X358661Y-194888D02*
Y-194088D01*
X633852Y-314567D02*
X634652D01*
X634252Y-314967D02*
Y-314167D01*
X652750Y-314567D02*
X653550D01*
X653150Y-314967D02*
Y-314167D01*
X508991Y-350636D02*
X509791D01*
X509391Y-351036D02*
Y-350236D01*
X508597Y-335675D02*
X509397D01*
X508997Y-336075D02*
Y-335275D01*
X678780Y0D02*
X691299D01*
X685039Y-6260D02*
Y6260D01*
X446844Y-324852D02*
X447644D01*
X447244Y-325252D02*
Y-324452D01*
X450781Y-324852D02*
X451581D01*
X451181Y-325252D02*
Y-324452D01*
X433458Y-324852D02*
X434258D01*
X433858Y-325252D02*
Y-324452D01*
X460230Y-324852D02*
X461030D01*
X460630Y-325252D02*
Y-324452D01*
X437395Y-324852D02*
X438195D01*
X437795Y-325252D02*
Y-324452D01*
X430702Y-324852D02*
X431502D01*
X431102Y-325252D02*
Y-324452D01*
X444088Y-324852D02*
X444888D01*
X444488Y-325252D02*
Y-324452D01*
X457080Y-324852D02*
X457880D01*
X457480Y-325252D02*
Y-324452D01*
X453537Y-324852D02*
X454337D01*
X453937Y-325252D02*
Y-324452D01*
X440151Y-324852D02*
X440951D01*
X440551Y-325252D02*
Y-324452D01*
X479961Y-340551D02*
X492480D01*
X486221Y-346811D02*
Y-334291D01*
X222238Y-374655D02*
X223038D01*
X222638Y-375055D02*
Y-374255D01*
X218045Y-374108D02*
X218845D01*
X218445Y-374507D02*
Y-373708D01*
X453537Y-306742D02*
X454337D01*
X453937Y-307142D02*
Y-306342D01*
X450781Y-306742D02*
X451581D01*
X451181Y-307142D02*
Y-306342D01*
X109009Y-140111D02*
X109809D01*
X109409Y-140511D02*
Y-139711D01*
X105009Y-140111D02*
X105809D01*
X105409Y-140511D02*
Y-139711D01*
X101010Y-140111D02*
X101810D01*
X101409Y-140511D02*
Y-139711D01*
X97009Y-140111D02*
X97809D01*
X97409Y-140511D02*
Y-139711D01*
X65545Y-57923D02*
X66345D01*
X65945Y-58323D02*
Y-57523D01*
X614757Y-8858D02*
X615557D01*
X615158Y-9258D02*
Y-8458D01*
X70466Y-122047D02*
X71266D01*
X70866Y-122447D02*
Y-121647D01*
X359804Y-252984D02*
X360604D01*
X360204Y-253384D02*
Y-252584D01*
X417196Y-175197D02*
X417996D01*
X417596Y-175597D02*
Y-174797D01*
X377521Y-203740D02*
X378321D01*
X377921Y-204140D02*
Y-203340D01*
X371616Y-200787D02*
X372416D01*
X372016Y-201187D02*
Y-200387D01*
X354141Y-223636D02*
X354941D01*
X354541Y-224036D02*
Y-223236D01*
X354052Y-235236D02*
X354852D01*
X354452Y-235636D02*
Y-234836D01*
X356178Y-225247D02*
X356978D01*
X356578Y-225647D02*
Y-224847D01*
X379521Y-201740D02*
X380321D01*
X379921Y-202140D02*
Y-201340D01*
X102128Y-211583D02*
X102928D01*
X102528Y-211983D02*
Y-211183D01*
X96725Y-219488D02*
X97525D01*
X97125Y-219888D02*
Y-219088D01*
X99010Y-216535D02*
X99809D01*
X99410Y-216935D02*
Y-216135D01*
X100978Y-214567D02*
X101778D01*
X101378Y-214967D02*
Y-214167D01*
X86214Y-175197D02*
X87014D01*
X86614Y-175597D02*
Y-174797D01*
X361252Y-235205D02*
X362052D01*
X361652Y-235605D02*
Y-234805D01*
X358731Y-223425D02*
X359531D01*
X359131Y-223825D02*
Y-223025D01*
X361131Y-223425D02*
X361931D01*
X361531Y-223825D02*
Y-223025D01*
X359836Y-262186D02*
X360636D01*
X360236Y-262586D02*
Y-261786D01*
X359836Y-266186D02*
X360636D01*
X360236Y-266586D02*
Y-265786D01*
X85016Y-317699D02*
X85816D01*
X85416Y-318099D02*
Y-317299D01*
X85230Y-263779D02*
X86030D01*
X85630Y-264179D02*
Y-263380D01*
X86162Y-211183D02*
X86962D01*
X86562Y-211583D02*
Y-210783D01*
X410643Y-174974D02*
X411443D01*
X411043Y-175374D02*
Y-174574D01*
X413039Y-174850D02*
X413839D01*
X413440Y-175250D02*
Y-174450D01*
X421196Y-175034D02*
X421996D01*
X421596Y-175434D02*
Y-174634D01*
X406128Y-157767D02*
X406928D01*
X406528Y-158167D02*
Y-157367D01*
X404128Y-163386D02*
X404928D01*
X404528Y-163786D02*
Y-162986D01*
X407080Y-160433D02*
X407880D01*
X407480Y-160833D02*
Y-160033D01*
X86214Y-221457D02*
X87014D01*
X86614Y-221857D02*
Y-221057D01*
X426765Y-175246D02*
X427565D01*
X427165Y-175646D02*
Y-174846D01*
X75387Y-232283D02*
X76187D01*
X75787Y-232683D02*
Y-231884D01*
X86767Y-166377D02*
X87567D01*
X87167Y-166777D02*
Y-165977D01*
X89167Y-166370D02*
X89967D01*
X89567Y-166770D02*
Y-165970D01*
X85230Y-213583D02*
X86030D01*
X85630Y-213983D02*
Y-213183D01*
X85230Y-266179D02*
X86030D01*
X85630Y-266580D02*
Y-265779D01*
X85230Y-320313D02*
X86030D01*
X85630Y-320713D02*
Y-319913D01*
X542876Y-226591D02*
X543676D01*
X543276Y-226991D02*
Y-226191D01*
X543894Y-224248D02*
X544694D01*
X544294Y-224648D02*
Y-223848D01*
X543891Y-233268D02*
X544691D01*
X544291Y-233668D02*
Y-232868D01*
X358852Y-235236D02*
X359652D01*
X359252Y-235636D02*
Y-234836D01*
X356452Y-235236D02*
X357252D01*
X356852Y-235636D02*
Y-234836D01*
X407080Y-163386D02*
X407880D01*
X407480Y-163786D02*
Y-162986D01*
X46844Y-8858D02*
X47644D01*
X47244Y-9258D02*
Y-8458D01*
X39954Y-8858D02*
X40754D01*
X40354Y-9258D02*
Y-8458D01*
X33065Y-8858D02*
X33865D01*
X33465Y-9258D02*
Y-8458D01*
X26175Y19685D02*
X26975D01*
X26575Y19285D02*
Y20085D01*
X86214Y-227362D02*
X87014D01*
X86614Y-227762D02*
Y-226962D01*
X63576Y-221457D02*
X64376D01*
X63976Y-221857D02*
Y-221057D01*
X82277Y-232283D02*
X83077D01*
X82677Y-232683D02*
Y-231884D01*
X63576Y-275590D02*
X64376D01*
X63976Y-275991D02*
Y-275190D01*
X75387Y-285433D02*
X76187D01*
X75787Y-285833D02*
Y-285033D01*
X87198Y-275590D02*
X87998D01*
X87598Y-275991D02*
Y-275190D01*
X87198Y-281496D02*
X87998D01*
X87598Y-281896D02*
Y-281096D01*
X81480Y-287582D02*
X82280D01*
X81880Y-287982D02*
Y-287182D01*
X62592Y-329724D02*
X63392D01*
X62992Y-330124D02*
Y-329324D01*
X74403Y-339567D02*
X75203D01*
X74803Y-339967D02*
Y-339167D01*
X78340Y-340551D02*
X79140D01*
X78740Y-340951D02*
Y-340151D01*
X87198Y-335630D02*
X87998D01*
X87598Y-336030D02*
Y-335230D01*
X87198Y-329724D02*
X87998D01*
X87598Y-330124D02*
Y-329324D01*
X63576Y-179134D02*
X64376D01*
X63976Y-179534D02*
Y-178734D01*
X74403Y-179134D02*
X75203D01*
X74803Y-179534D02*
Y-178734D01*
X86162Y-169257D02*
X86962D01*
X86562Y-169657D02*
Y-168857D01*
X80309Y-180118D02*
X81109D01*
X80709Y-180518D02*
Y-179718D01*
X26175Y-283465D02*
X26975D01*
X26575Y-283865D02*
Y-283065D01*
X30112Y-170276D02*
X30912D01*
X30512Y-170676D02*
Y-169876D01*
X323450Y-241173D02*
X324250D01*
X323850Y-241573D02*
Y-240773D01*
X323450Y-237205D02*
X324250D01*
X323850Y-237605D02*
Y-236805D01*
X323419Y-231299D02*
X324219D01*
X323819Y-231699D02*
Y-230899D01*
X325387Y-229362D02*
X326187D01*
X325787Y-229762D02*
Y-228962D01*
X323419Y-227362D02*
X324219D01*
X323819Y-227762D02*
Y-226962D01*
X325387Y-239205D02*
X326187D01*
X325787Y-239605D02*
Y-238805D01*
X-24022Y-342520D02*
X-23222D01*
X-23622Y-342920D02*
Y-342120D01*
X89167Y-140270D02*
X89967D01*
X89567Y-140670D02*
Y-139870D01*
X86854Y-139629D02*
X87654D01*
X87254Y-140029D02*
Y-139229D01*
X118694Y-130047D02*
X119494D01*
X119095Y-130447D02*
Y-129647D01*
X116726Y-132047D02*
X117526D01*
X117126Y-132447D02*
Y-131647D01*
X106947Y-110236D02*
X107747D01*
X107346Y-110636D02*
Y-109836D01*
X104946Y-112205D02*
X105746D01*
X105347Y-112605D02*
Y-111805D01*
X98946Y-110236D02*
X99747D01*
X99347Y-110636D02*
Y-109836D01*
X109010Y-112236D02*
X109810D01*
X109409Y-112636D02*
Y-111836D01*
X118694Y-122047D02*
X119494D01*
X119095Y-122447D02*
Y-121647D01*
X-24022Y-229331D02*
X-23222D01*
X-23622Y-229731D02*
Y-228931D01*
X-24022Y-233268D02*
X-23222D01*
X-23622Y-233668D02*
Y-232868D01*
X-24022Y-237205D02*
X-23222D01*
X-23622Y-237605D02*
Y-236805D01*
X-24022Y-241142D02*
X-23222D01*
X-23622Y-241542D02*
Y-240742D01*
X-24022Y-282480D02*
X-23222D01*
X-23622Y-282880D02*
Y-282080D01*
X-24022Y-286417D02*
X-23222D01*
X-23622Y-286817D02*
Y-286017D01*
X-24022Y-290354D02*
X-23222D01*
X-23622Y-290754D02*
Y-289954D01*
X-24022Y-294291D02*
X-23222D01*
X-23622Y-294691D02*
Y-293891D01*
X-24022Y-335630D02*
X-23222D01*
X-23622Y-336030D02*
Y-335230D01*
X-24022Y-339567D02*
X-23222D01*
X-23622Y-339967D02*
Y-339167D01*
X-24022Y-346457D02*
X-23222D01*
X-23622Y-346857D02*
Y-346057D01*
X107009Y-141732D02*
X107809D01*
X107409Y-142132D02*
Y-141332D01*
X99010Y-141732D02*
X99809D01*
X99410Y-142132D02*
Y-141332D01*
X-24022Y-70866D02*
X-23222D01*
X-23622Y-71266D02*
Y-70466D01*
X-24022Y-66929D02*
X-23222D01*
X-23622Y-67329D02*
Y-66529D01*
X-24022Y-62992D02*
X-23222D01*
X-23622Y-63392D02*
Y-62592D01*
X-24022Y-60039D02*
X-23222D01*
X-23622Y-60439D02*
Y-59639D01*
X-24022Y-102362D02*
X-23222D01*
X-23622Y-102762D02*
Y-101962D01*
X-24022Y-106299D02*
X-23222D01*
X-23622Y-106699D02*
Y-105899D01*
X-24022Y-110236D02*
X-23222D01*
X-23622Y-110636D02*
Y-109836D01*
X-24022Y-114173D02*
X-23222D01*
X-23622Y-114573D02*
Y-113773D01*
X-24022Y-187992D02*
X-23222D01*
X-23622Y-188392D02*
Y-187592D01*
X-24022Y-184055D02*
X-23222D01*
X-23622Y-184455D02*
Y-183655D01*
X-24022Y-181102D02*
X-23222D01*
X-23622Y-181502D02*
Y-180702D01*
X-24022Y-177165D02*
X-23222D01*
X-23622Y-177565D02*
Y-176765D01*
X116726Y-128047D02*
X117526D01*
X117126Y-128447D02*
Y-127647D01*
X116726Y-124047D02*
X117526D01*
X117126Y-124447D02*
Y-123647D01*
X116726Y-119921D02*
X117526D01*
X117126Y-120321D02*
Y-119521D01*
X100883Y-112205D02*
X101683D01*
X101284Y-112605D02*
Y-111805D01*
X96883Y-112205D02*
X97684D01*
X97284Y-112605D02*
Y-111805D01*
X645445Y-95108D02*
X657645D01*
X651545Y-101208D02*
Y-89008D01*
X407256Y7254D02*
X419456D01*
X413356Y1154D02*
Y13354D01*
X407256Y-95108D02*
X419456D01*
X413356Y-101208D02*
Y-89008D01*
X645445Y7254D02*
X657645D01*
X651545Y1154D02*
Y13354D01*
X65780Y7412D02*
X77980D01*
X71880Y1312D02*
Y13512D01*
X303969Y-94950D02*
X316169D01*
X310069Y-101050D02*
Y-88850D01*
X303969Y7412D02*
X316169D01*
X310069Y1312D02*
Y13512D01*
X65780Y-94950D02*
X77980D01*
X71880Y-101050D02*
Y-88850D01*
X98622Y-121653D02*
X99410D01*
X99016Y-122047D02*
Y-121260D01*
X102953Y-121653D02*
X103740D01*
X103347Y-122047D02*
Y-121260D01*
X107283Y-121653D02*
X108071D01*
X107677Y-122047D02*
Y-121260D01*
X98622Y-125984D02*
X99410D01*
X99016Y-126378D02*
Y-125591D01*
X102953Y-125984D02*
X103740D01*
X103347Y-126378D02*
Y-125591D01*
X107283Y-125984D02*
X108071D01*
X107677Y-126378D02*
Y-125591D01*
X98622Y-130315D02*
X99410D01*
X99016Y-130709D02*
Y-129921D01*
X102953Y-130315D02*
X103740D01*
X103347Y-130709D02*
Y-129921D01*
X107283Y-130315D02*
X108071D01*
X107677Y-130709D02*
Y-129921D01*
X543891Y-195718D02*
X544691D01*
X544291Y-196118D02*
Y-195318D01*
X469121Y-137615D02*
X469921D01*
X469521Y-138015D02*
Y-137215D01*
X533478Y-117716D02*
X534278D01*
X533878Y-118116D02*
Y-117316D01*
X524206Y-125836D02*
X525006D01*
X524606Y-126236D02*
Y-125436D01*
X524157Y-128740D02*
X524957D01*
X524557Y-129140D02*
Y-128340D01*
X450450Y-174127D02*
X451250D01*
X450850Y-174527D02*
Y-173727D01*
X512395Y-104214D02*
X513195D01*
X512795Y-104614D02*
Y-103814D01*
X463151Y-116025D02*
X463951D01*
X463551Y-116425D02*
Y-115625D01*
X658065Y-37647D02*
X658865D01*
X658465Y-38047D02*
Y-37247D01*
X658065Y-29773D02*
X658865D01*
X658465Y-30173D02*
Y-29373D01*
X624600Y-21899D02*
X625400D01*
X625000Y-22299D02*
Y-21499D01*
X189954Y-377411D02*
X190754D01*
X190354Y-377811D02*
Y-377011D01*
X314561Y-118947D02*
X315361D01*
X314961Y-119346D02*
Y-118546D01*
X430407Y-175344D02*
X431207D01*
X430807Y-175744D02*
Y-174944D01*
X308616Y-128659D02*
X309416D01*
X309016Y-129059D02*
Y-128259D01*
X418498Y-144143D02*
X419298D01*
X418898Y-144543D02*
Y-143743D01*
X415705Y-144180D02*
X416505D01*
X416106Y-144580D02*
Y-143780D01*
X398168Y-145083D02*
X398968D01*
X398568Y-145483D02*
Y-144683D01*
X210033Y-374655D02*
X210833D01*
X210433Y-375055D02*
Y-374255D01*
X206096Y-374655D02*
X206896D01*
X206496Y-375055D02*
Y-374255D01*
X441726Y-306742D02*
X442526D01*
X442126Y-307142D02*
Y-306342D01*
X438970Y-306742D02*
X439770D01*
X439370Y-307142D02*
Y-306342D01*
X237592Y-374655D02*
X238392D01*
X237992Y-375055D02*
Y-374255D01*
X241529Y-374655D02*
X242329D01*
X241929Y-375055D02*
Y-374255D01*
X253255Y-374421D02*
X254055D01*
X253655Y-374821D02*
Y-374021D01*
X256490Y-374655D02*
X257290D01*
X256890Y-375055D02*
Y-374255D01*
X273025Y-374655D02*
X273825D01*
X273425Y-375055D02*
Y-374255D01*
X269102Y-374291D02*
X269902D01*
X269502Y-374691D02*
Y-373891D01*
X245939Y-386975D02*
X246739D01*
X246339Y-387375D02*
Y-386575D01*
X249009Y-387253D02*
X249810D01*
X249410Y-387653D02*
Y-386854D01*
X232080Y-387253D02*
X232880D01*
X232480Y-387653D02*
Y-386854D01*
X228931Y-387253D02*
X229731D01*
X229331Y-387653D02*
Y-386854D01*
X435820Y-306742D02*
X436621D01*
X436221Y-307142D02*
Y-306342D01*
X212395Y-387253D02*
X213195D01*
X212795Y-387653D02*
Y-386854D01*
X433065Y-306742D02*
X433865D01*
X433465Y-307142D02*
Y-306342D01*
X215545Y-387253D02*
X216345D01*
X215945Y-387653D02*
Y-386854D01*
X261606Y-387255D02*
X262406D01*
X262006Y-387655D02*
Y-386855D01*
X447632Y-306742D02*
X448431D01*
X448032Y-307142D02*
Y-306342D01*
X264757Y-387253D02*
X265558D01*
X265158Y-387653D02*
Y-386854D01*
X444876Y-306742D02*
X445676D01*
X445276Y-307142D02*
Y-306342D01*
X104128Y-92175D02*
X104928D01*
X104528Y-92575D02*
Y-91775D01*
X269285Y-106151D02*
X270085D01*
X269685Y-106551D02*
Y-105751D01*
X131490Y-72687D02*
X132290D01*
X131890Y-73087D02*
Y-72287D01*
X178734Y-386466D02*
X179534D01*
X179134Y-386866D02*
Y-386066D01*
X178734Y-389616D02*
X179534D01*
X179134Y-390016D02*
Y-389216D01*
X178143Y-377411D02*
X178943D01*
X178543Y-377811D02*
Y-377011D01*
X443498Y-175049D02*
X444298D01*
X443898Y-175449D02*
Y-174649D01*
X99010Y-65797D02*
X99809D01*
X99410Y-66197D02*
Y-65397D01*
X99010Y-57923D02*
X99809D01*
X99410Y-58323D02*
Y-57523D01*
X65545Y-65797D02*
X66345D01*
X65945Y-66197D02*
Y-65397D01*
X65545Y-50049D02*
X66345D01*
X65945Y-50449D02*
Y-49649D01*
X78340Y-238041D02*
X79140D01*
X78740Y-238441D02*
Y-237641D01*
X33065Y19833D02*
X33865D01*
X33465Y19433D02*
Y20233D01*
X39954Y19685D02*
X40754D01*
X40354Y19285D02*
Y20085D01*
X46844Y19685D02*
X47644D01*
X47244Y19285D02*
Y20085D01*
X456342Y-116043D02*
X457142D01*
X456742Y-116443D02*
Y-115643D01*
X463928Y-146397D02*
X464728D01*
X464328Y-146797D02*
Y-145997D01*
X468891Y-143848D02*
X469691D01*
X469291Y-144248D02*
Y-143448D01*
X460919Y-143750D02*
X461719D01*
X461319Y-144150D02*
Y-143350D01*
X456883Y-175147D02*
X457684D01*
X457283Y-175547D02*
Y-174747D01*
X468990Y-175147D02*
X469790D01*
X469390Y-175547D02*
Y-174747D01*
X543891Y-215403D02*
X544691D01*
X544291Y-215803D02*
Y-215003D01*
X512002Y-261958D02*
X512802D01*
X512402Y-262358D02*
Y-261558D01*
X512002Y-265108D02*
X512802D01*
X512402Y-265508D02*
Y-264708D01*
X512143Y-268065D02*
X512943D01*
X512543Y-268465D02*
Y-267665D01*
X437297Y-175246D02*
X438097D01*
X437697Y-175646D02*
Y-174846D01*
X433458Y-175246D02*
X434258D01*
X433858Y-175646D02*
Y-174846D01*
X404423Y-175344D02*
X405223D01*
X404823Y-175744D02*
Y-174944D01*
X401864Y-175344D02*
X402664D01*
X402264Y-175744D02*
Y-174944D01*
X308616Y-113986D02*
X309416D01*
X309016Y-114386D02*
Y-113586D01*
X193498Y-115009D02*
X194298D01*
X193898Y-115409D02*
Y-114609D01*
X193498Y-119931D02*
X194298D01*
X193898Y-120331D02*
Y-119531D01*
X308655Y-123868D02*
X309455D01*
X309055Y-124268D02*
Y-123468D01*
X182277Y-386466D02*
X183077D01*
X182677Y-386866D02*
Y-386066D01*
X186214Y-386466D02*
X187014D01*
X186614Y-386866D02*
Y-386066D01*
X182277Y-389616D02*
X183077D01*
X182677Y-390016D02*
Y-389216D01*
X186214Y-389616D02*
X187014D01*
X186614Y-390016D02*
Y-389216D01*
M02*
